FILE_TYPE = MULTI_PHYS_TABLE;

PART 'Q_INDUCTOR'

{========================================================================================}
:VALUE                          | PACK_TYPE  | MATERIAL | PART_NUMBER                = STANDARD        | LIFECYCLE          | PART_NUMBER                | JEDEC_TYPE                        | VALUE                          | CLASS      | DESCRIPTION                                     | COMPONENT_TYPE | LEAD_LENGTH | LPID | DAY          ;
{========================================================================================}
 '0.2UH'                        | 'TH'       | 'IND'    | 'TMP_QDC+20K0M000'(!)      = 'Non-Preferred' | 'End of Life'      | 'DC+20K0M000'              |'LC7_P8XA_EOL'| '0.2UH'                        | 'DISCRETE' | 'INDUCTOR 0.2UH'                                | 'THMT'         | ''          | ''   | ''          
 '0.2UH'                        | 'TH'       | 'EMPTY'  | 'TMP_QDC+20K0M000'(!)      = 'Non-Preferred' | 'End of Life'      | 'DC+20K0M000'              |'LC7_P8XA_EOL'| 'NA'                           | 'IO'       | 'INDUCTOR 0.2UH'                                | 'THMT'         | ''          | ''   | ''          
 '0.2UH'                        | 'TH_SEL'   | 'IND'    | 'TMP_QDC+20K0M000'(!)      = 'Non-Preferred' | 'End of Life'      | 'DC+20K0M000'              |'G_LC7_P8XA_I_T2B_EOL'| '0.2UH'                        | 'DISCRETE' | 'INDUCTOR 0.2UH'                                | 'THMT'         | ''          | ''   | '20100820'  
 '0.2UH'                        | 'TH_SEL'   | 'EMPTY'  | 'TMP_QDC+20K0M000'(!)      = 'Non-Preferred' | 'End of Life'      | 'DC+20K0M000'              |'G_LC7_P8XA_I_T2B_EOL'| 'NA'                           | 'IO'       | 'INDUCTOR 0.2UH'                                | 'THMT'         | ''          | ''   | '20100820'  
 '10UH'                         | 'SMLF'     | 'IND'    | 'TMP_QCV01001MZ02'(!)      = 'End of Design' | 'Comp-Approve'     | 'CV01001MZ02'              |'L0603'| '10UH'                         | 'DISCRETE' | 'INDUCTOR 10UH'                                 | 'CHIP0603'     | ''          | ''   | ''          
 '10UH'                         | 'SMLF'     | 'EMPTY'  | 'TMP_QCV01001MZ02'(!)      = 'End of Design' | 'Comp-Approve'     | 'CV01001MZ02'              |'L0603'| 'NA'                           | 'IO'       | 'INDUCTOR 10UH'                                 | 'CHIP0603'     | ''          | ''   | ''          
 'BLM31PG601SN1L'               | 'SMLF'     | 'IND'    | 'TMP_QCX1PG601016'(!)      = ''              | ''                 | 'CX1PG601016'              |'L1206'| 'BLM31PG601SN1L'               | 'DISCRETE' | 'BLM31PG601SN1L'                                | 'CHIP'         | ''          | ''   | ''          
 'BLM31PG601SN1L'               | 'SMLF'     | 'EMPTY'  | 'TMP_QCX1PG601016'(!)      = ''              | ''                 | 'CX1PG601016'              |'L1206'| 'NA'                           | 'IO'       | 'BLM31PG601SN1L'                                | 'CHIP'         | ''          | ''   | ''          
 '1.8UH'                        | 'SMLF'     | 'IND'    | 'TMP_QDC-18K0M000'(!)      = ''              | ''                 | 'DC-18K0M000'              |'LC16-5_P6XA'| '1.8UH'                        | 'DISCRETE' | 'CHOKE 1.8U 20A+-20%(WM44SF36Q-110109Y-U)'      | 'THMT'         | ''          | ''   | ''          
 '1.8UH'                        | 'SMLF'     | 'EMPTY'  | 'TMP_QDC-18K0M000'(!)      = ''              | ''                 | 'DC-18K0M000'              |'LC16-5_P6XA'| 'NA'                           | 'IO'       | 'CHOKE 1.8U 20A+-20%(WM44SF36Q-110109Y-U)'      | 'THMT'         | ''          | ''   | ''          
 '0.33UH'                       | 'SMLF'     | 'IND'    | 'TMP_QCV+33K0MZ28'(!)      = 'End of Design' | 'End of Life'      | 'CV+33K0MZ28'              |'L_MPL73_EOL'| '0.33UH'                       | 'DISCRETE' | 'IND 0.33UH +-20% 20A( MPL73-R33)'              | 'CHIP'         | ''          | ''   | ''          
 '0.33UH'                       | 'SMLF'     | 'EMPTY'  | 'TMP_QCV+33K0MZ28'(!)      = 'End of Design' | 'End of Life'      | 'CV+33K0MZ28'              |'L_MPL73_EOL'| 'NA'                           | 'IO'       | 'IND 0.33UH +-20% 20A( MPL73-R33)'              | 'CHIP'         | ''          | ''   | ''          
 '3.3UH'                        | 'SMLF'     | 'IND'    | 'TMP_QCV-3383MZ01'(!)      = ''              | ''                 | 'CV-3383MZ01'              |'L_KJ07XA'| '3.3UH'                        | 'DISCRETE' | 'IND SMD 3.3UH+-20% 8.3A(KJ0760-3R3M)'          | 'CHIP'         | ''          | ''   | ''          
 '3.3UH'                        | 'SMLF'     | 'EMPTY'  | 'TMP_QCV-3383MZ01'(!)      = ''              | ''                 | 'CV-3383MZ01'              |'L_KJ07XA'| 'NA'                           | 'IO'       | 'IND SMD 3.3UH+-20% 8.3A(KJ0760-3R3M)'          | 'CHIP'         | ''          | ''   | ''          
 '7UH'                          | 'SMLF'     | 'IND'    | 'TMP_QCV-7048TZ25'(!)      = 'End of Design' | 'End of Life'      | 'CV-7048TZ25'              |'L_SIL104R_EOL'| '7UH'                          | 'DISCRETE' | 'IND SMD 7.0UH 30% 4.8A(SIL104R-7R0PF)L-F'      | 'CHIP'         | ''          | ''   | ''          
 '7UH'                          | 'SMLF'     | 'EMPTY'  | 'TMP_QCV-7048TZ25'(!)      = 'End of Design' | 'End of Life'      | 'CV-7048TZ25'              |'L_SIL104R_EOL'| 'NA'                           | 'IO'       | 'IND SMD 7.0UH 30% 4.8A(SIL104R-7R0PF)L-F'      | 'CHIP'         | ''          | ''   | ''          
 'BLM18PG181SN1D'               | 'SMLF'     | 'IND'    | 'TMP_QCX8PG181001'(!)      = 'End of Design' | 'Comp-Approve'     | 'CX8PG181001'              |'L0603'| 'BLM18PG181SN1D'               | 'DISCRETE' | 'EMI FILTER BLM18PG181SN1D(180,1500MA)'         | 'CHIP'         | ''          | ''   | ''          
 'BLM18PG181SN1D'               | 'SMLF'     | 'EMPTY'  | 'TMP_QCX8PG181001'(!)      = 'End of Design' | 'Comp-Approve'     | 'CX8PG181001'              |'L0603'| 'NA'                           | 'IO'       | 'IND SMD 7.0UH 30% 4.8A(SIL104R-7R0PF)L-F'      | 'CHIP'         | ''          | ''   | ''          
 '1.2UH'                        | 'SMLF'     | 'IND'    | 'TMP_QDC-12^0M002'(!)      = ''              | ''                 | 'DC-12^0M002'              |'LC18_P7-5B'| '1.2UH'                        | 'DISCRETE' | 'CHOKE 1.2U+-20% 40A(APU105014008P-1R2MU)'      | 'CHIP'         | ''          | ''   | ''          
 '1.2UH'                        | 'SMLF'     | 'EMPTY'  | 'TMP_QDC-12^0M002'(!)      = ''              | ''                 | 'DC-12^0M002'              |'LC18_P7-5B'| 'NA'                           | 'IO'       | 'CHOKE 1.2U+-20% 40A(APU105014008P-1R2MU)'      | 'CHIP'         | ''          | ''   | ''          
 '2.5UH'                        | 'SMLF'     | 'IND'    | 'TMP_QCV-2575MZ02'(!)      = ''              | ''                 | 'CV-2575MZ02'              |'L_MSCDRI104R'| '2.5UH'                        | 'DISCRETE' | 'IND SMD 2.5U 20%7.5A(MSCDRI-104R-2R5M)'        | 'CHIP'         | ''          | ''   | ''          
 '2.5UH'                        | 'SMLF'     | 'EMPTY'  | 'TMP_QCV-2575MZ02'(!)      = ''              | ''                 | 'CV-2575MZ02'              |'L_MSCDRI104R'| 'NA'                           | 'IO'       | 'IND SMD 2.5U 20%7.5A(MSCDRI-104R-2R5M)'        | 'CHIP'         | ''          | ''   | ''          
 '7UH'                          | 'SMLF'     | 'IND'    | 'TMP_QCV-7048MZ01'(!)      = ''              | ''                 | 'CV-7048MZ01'              |'L_MSCDRI104R'| '7UH'                          | 'DISCRETE' | 'IND SMD 7UH 20% 4.8A(MSCDRI-104R-7R0M)'        | 'CHIP'         | ''          | ''   | ''          
 '7UH'                          | 'SMLF'     | 'EMPTY'  | 'TMP_QCV-7048MZ01'(!)      = ''              | ''                 | 'CV-7048MZ01'              |'L_MSCDRI104R'| 'NA'                           | 'IO'       | 'IND SMD 7UH 20% 4.8A(MSCDRI-104R-7R0M)'        | 'CHIP'         | ''          | ''   | ''          
 '1.8UH'                        | 'SMLF'     | 'IND'    | 'TMP_QDC-18K0M002'(!)      = ''              | ''                 | 'DC-18K0M002'              |'LC15_P6A'| '1.8UH'                        | 'DISCRETE' | 'CHOKE 1.8U 20A+-20%(APU104417010P-1R8MU)'      | 'CHIP'         | ''          | ''   | ''          
 '1.8UH'                        | 'SMLF'     | 'EMPTY'  | 'TMP_QDC-18K0M002'(!)      = ''              | ''                 | 'DC-18K0M002'              |'LC15_P6A'| 'NA'                           | 'IO'       | 'CHOKE 1.8U 20A+-20%(APU104417010P-1R8MU)'      | 'CHIP'         | ''          | ''   | ''          
 '3.3UH'                        | 'SMLF'     | 'IND'    | 'TMP_QCV-3321MZ00'(!)      = ''              | ''                 | 'CV-3321MZ00'              |'L_MSCD43'| '3.3UH'                        | 'DISCRETE' | 'IND SMD 3.3UH,+-20% 2.15A(FPI0403)'            | 'CHIP'         | ''          | ''   | ''          
 '3.3UH'                        | 'SMLF'     | 'EMPTY'  | 'TMP_QCV-3321MZ00'(!)      = ''              | ''                 | 'CV-3321MZ00'              |'L_MSCD43'| 'NA'                           | 'IO'       | 'IND SMD 3.3UH,+-20% 2.15A(FPI0403)'            | 'CHIP'         | ''          | ''   | ''          
 '0.4UH'                        | 'THLF'     | 'IND'    | 'TMP_QDC+40K0M009'(!)      = 'Non-Preferred' | 'End of Life'      | 'DC+40K0M009'              |'LC12_P8_EOL'| '0.4UH'                        | 'DISCRETE' | 'CHOKE 0.4U 20A+-20%(WR0412)'                   | 'CHIP'         | ''          | ''   | ''          
 '0.4UH'                        | 'THLF'     | 'EMPTY'  | 'TMP_QDC+40K0M009'(!)      = 'Non-Preferred' | 'End of Life'      | 'DC+40K0M009'              |'LC12_P8_EOL'| 'NA'                           | 'IO'       | 'CHOKE 0.4U 20A+-20%(WR0412)'                   | 'CHIP'         | ''          | ''   | ''          
 '4.7UH'                        | 'THLF'     | 'IND'    | 'TMP_QCV-47A0MD00'(!)      = ''              | ''                 | 'CV-47A0MD00'              |'LC10_P8XA'| '4.7UH'                        | 'DISCRETE' | 'IND DIP 4.7U +-20%,10A(KQ10VC-4R7M)'           | 'CHIP'         | ''          | ''   | ''          
 '4.7UH'                        | 'THLF'     | 'EMPTY'  | 'TMP_QCV-47A0MD00'(!)      = ''              | ''                 | 'CV-47A0MD00'              |'LC10_P8XA'| 'NA'                           | 'IO'       | 'IND DIP 4.7U +-20%,10A(KQ10VC-4R7M)'           | 'CHIP'         | ''          | ''   | ''          
 'HB-1S1005-100JT'              | 'SMLF'     | 'IND'    | 'TMP_QCX0100JT000'(!)      = 'End of Design' | 'Comp-Approve'     | 'CX0100JT000'              |'L0402'| 'HB-1S1005-100JT'              | 'DISCRETE' | 'EMI FILTER HB-1S1005-100JT(10,500MA)'          | 'CHIP'         | ''          | ''   | ''          
 'HB-1S1005-100JT'              | 'SMLF'     | 'EMPTY'  | 'TMP_QCX0100JT000'(!)      = 'End of Design' | 'Comp-Approve'     | 'CX0100JT000'              |'L0402'| 'NA'                           | 'IO'       | 'EMI FILTER HB-1S1005-100JT(10,500MA)'          | 'CHIP'         | ''          | ''   | ''          
 'SBK160808T-100Y-N'            | 'SMLF'     | 'IND'    | 'TMP_QCX08T100001'(!)      = ''              | ''                 | 'CX08T100001'              |'L0603'| 'SBK160808T-100Y-N'            | 'DISCRETE' | 'EMI FILTER SBK160808T-100Y-N(10,500MA)'        | 'CHIP'         | ''          | ''   | ''          
 'SBK160808T-100Y-N'            | 'SMLF'     | 'EMPTY'  | 'TMP_QCX08T100001'(!)      = ''              | ''                 | 'CX08T100001'              |'L0603'| 'NA'                           | 'IO'       | 'EMI FILTER SBK160808T-100Y-N(10,500MA)'        | 'CHIP'         | ''          | ''   | ''          
 '0.45UH'                       | 'SMLF'     | 'IND'    | 'TMP_QCV+45^0MZ05'(!)      = ''              | ''                 | 'CV+45^0MZ05'              |'L_SIHH1309'| '0.45UH'                       | 'DISCRETE' | 'IND SMD 0.45U 20% 45A(SIHH1309-R45M)'          | 'CHIP'         | ''          | ''   | ''          
 '0.45UH'                       | 'SMLF'     | 'EMPTY'  | 'TMP_QCV+45^0MZ05'(!)      = ''              | ''                 | 'CV+45^0MZ05'              |'L_SIHH1309'| 'NA'                           | 'IO'       | 'IND SMD 0.45U 20% 45A(SIHH1309-R45M)'          | 'CHIP'         | ''          | ''   | ''          
 'BLM15HD182SN1D'               | 'SMLF'     | 'IND'    | 'TMP_QCX5HD182000'(!)      = ''              | ''                 | 'CX5HD182000'              |'L0402'| '1800'                         | 'DISCRETE' | 'EMI FILTER BLM15HD182SN1D(1800,200MA)'         | 'CHIP'         | ''          | ''   | ''          
 'BLM15HD182SN1D'               | 'SMLF'     | 'EMPTY'  | 'TMP_QCX5HD182000'(!)      = ''              | ''                 | 'CX5HD182000'              |'L0402'| 'NA'                           | 'IO'       | 'EMI FILTER BLM15HD182SN1D(1800,200MA)'         | 'CHIP'         | ''          | ''   | ''          
 'MPZ2012S331ATA'               | 'SMLF'     | 'IND'    | 'TMP_QCX12S331006'(!)      = 'End of Design' | 'End of Life'      | 'CX12S331006'              |'L0805_EOL'| '330'                          | 'DISCRETE' | 'EMI FIL CHIP MPZ2012S331ATA(330,2.5A)'         | 'CHIP'         | ''          | ''   | ''          
 'MPZ2012S331ATA'               | 'SMLF'     | 'EMPTY'  | 'TMP_QCX12S331006'(!)      = 'End of Design' | 'End of Life'      | 'CX12S331006'              |'L0805_EOL'| 'NA'                           | 'IO'       | 'EMI FIL CHIP MPZ2012S331ATA(330,2.5A)'         | 'CHIP'         | ''          | ''   | ''          
 'MPZ2012S101AT'                | 'SMLF'     | 'IND'    | 'TMP_QCX12S101001'(!)      = 'End of Design' | 'End of Life'      | 'CX12S101001'              |'L0805_EOL'| '100'                          | 'DISCRETE' | 'EMI FIL CHIP MPZ2012S101AT(100,4A)L-F'         | 'CHIP'         | ''          | ''   | ''          
 'MPZ2012S101AT'                | 'SMLF'     | 'EMPTY'  | 'TMP_QCX12S101001'(!)      = 'End of Design' | 'End of Life'      | 'CX12S101001'              |'L0805_EOL'| 'NA'                           | 'IO'       | 'EMI FIL CHIP MPZ2012S101AT(100,4A)L-F'         | 'CHIP'         | ''          | ''   | ''          
 'BLM18BD601SN1D'               | 'SMLF'     | 'IND'    | 'TMP_QCX8BD601001'(!)      = ''              | ''                 | 'CX8BD601001'              |'L0603'| 'BLM18BD601SN1D'               | 'DISCRETE' | 'EMI FILTER CHIP BLM18BD601SN1D(0603)'          | 'CHIP'         | ''          | ''   | ''          
 'BLM18BD601SN1D'               | 'SMLF'     | 'EMPTY'  | 'TMP_QCX8BD601001'(!)      = ''              | ''                 | 'CX8BD601001'              |'L0603'| 'NA'                           | 'IO'       | 'EMI FILTER CHIP BLM18BD601SN1D(0603)'          | 'CHIP'         | ''          | ''   | ''          
 'BLM18PG300SN1D '              | 'SMLF'     | 'IND'    | 'TMP_QCX8PG300001'(!)      = ''              | ''                 | 'CX8PG300001'              |'L0603'| 'BLM18PG300SN1D '              | 'DISCRETE' | 'EMI FILTER SBK160808T-100Y-N(10,500MA)'        | 'CHIP'         | ''          | ''   | ''          
 'BLM18PG300SN1D '              | 'SMLF'     | 'EMPTY'  | 'TMP_QCX8PG300001'(!)      = ''              | ''                 | 'CX8PG300001'              |'L0603'| 'NA'                           | 'IO'       | 'EMI FILTER SBK160808T-100Y-N(10,500MA)'        | 'CHIP'         | ''          | ''   | ''          
 '4.7UH '                       | 'SMLF'     | 'IND'    | 'TMP_QCV-4706MZ00'(!)      = ''              | ''                 | 'CV-4706MZ00'              |'L1007XA'| '4.7UH '                       | 'DISCRETE' | 'IND SMD 4.7UH 20% 510MA'                       | 'CHIP'         | ''          | ''   | ''          
 '4.7UH '                       | 'SMLF'     | 'EMPTY'  | 'TMP_QCV-4706MZ00'(!)      = ''              | ''                 | 'CV-4706MZ00'              |'L1007XA'| 'NA'                           | 'IO'       | 'IND SMD 4.7UH 20% 510MA'                       | 'CHIP'         | ''          | ''   | ''          
 '0.88UH'                       | 'SMLF'     | 'IND'    | 'TMP_QDC+88K0M009'(!)      = 'Standard'      | 'End of Life'      | 'DC+88K0M009'              |'L_PCMC104T_EOL'| '0.88UH'                       | 'DISCRETE' | 'CHOKE COIL 0.88UH,20%20A(PCMC104T-R88MN)'      | 'CHIP'         | ''          | ''   | ''          
 '0.88UH'                       | 'SMLF'     | 'EMPTY'  | 'TMP_QDC+88K0M009'(!)      = 'Standard'      | 'End of Life'      | 'DC+88K0M009'              |'L_PCMC104T_EOL'| 'NA'                           | 'IO'       | 'CHOKE COIL 0.88UH,20%20A(PCMC104T-R88MN)'      | 'CHIP'         | ''          | ''   | ''          
 '10UH'                         | 'SMLF'     | 'IND'    | 'TMP_QCV01005KZ00'(!)      = ''              | ''                 | 'CV01005KZ00'              |'L_1210XA'| '10UH'                         | 'DISCRETE' | 'IND SMD 10U +-10% 450MA(NLCV32T-100K-PF)'      | 'CHIP'         | ''          | ''   | ''          
 '10UH'                         | 'SMLF'     | 'EMPTY'  | 'TMP_QCV01005KZ00'(!)      = ''              | ''                 | 'CV01005KZ00'              |'L_1210XA'| 'NA'                           | 'IO'       | 'IND SMD 10U +-10% 450MA(NLCV32T-100K-PF)'      | 'CHIP'         | ''          | ''   | ''          
 'BLM21AG601SN1D'               | 'SMLF'     | 'IND'    | 'TMP_QCX21AG60008'(!)      = 'End of Design' | 'Comp-Approve'     | 'CX21AG60008'              |'L0805'| 'BLM21AG601SN1D'               | 'DISCRETE' | 'EMI FILTER BLM21AG601SN1D(0.2A,600)'           | 'CHIP'         | ''          | ''   | ''          
 'BLM21AG601SN1D'               | 'SMLF'     | 'EMPTY'  | 'TMP_QCX21AG60008'(!)      = 'End of Design' | 'Comp-Approve'     | 'CX21AG60008'              |'L0805'| 'NA'                           | 'IO'       | 'EMI FILTER BLM21AG601SN1D(0.2A,600)'           | 'CHIP'         | ''          | ''   | ''          
 'BLM18AG601SN1D '              | 'SMLF'     | 'IND'    | 'TMP_QCW8AG601009'(!)      = ''              | 'End of Life'      | 'CW8AG601009'              |'L0603_EOL'| 'BLM18AG601SN1D '              | 'DISCRETE' | 'FERRITE BEAD BLM18AG601SN1D (200M)'            | 'CHIP'         | ''          | ''   | ''          
 'BLM18AG601SN1D '              | 'SMLF'     | 'EMPTY'  | 'TMP_QCW8AG601009'(!)      = ''              | 'End of Life'      | 'CW8AG601009'              |'L0603_EOL'| 'NA'                           | 'IO'       | 'FERRITE BEAD BLM18AG601SN1D (200M)'            | 'CHIP'         | ''          | ''   | ''          
 '1UH'                          | 'SMLF'     | 'IND'    | 'TMP_QCV-10B0MZ02'(!)      = 'End of Design' | 'End of Life'      | 'CV-10B0MZ02'              |'L_MPL73_EOL'| '1UH'                          | 'DISCRETE' | 'CHOKE COIL 0.88UH,20%20A(PCMC104T-R88MN)'      | 'CHIP'         | ''          | ''   | ''          
 '1UH'                          | 'SMLF'     | 'EMPTY'  | 'TMP_QCV-10B0MZ02'(!)      = 'End of Design' | 'End of Life'      | 'CV-10B0MZ02'              |'L_MPL73_EOL'| 'NA'                           | 'IO'       | 'CHOKE COIL 0.88UH,20%20A(PCMC104T-R88MN)'      | 'CHIP'         | ''          | ''   | ''          
 'BLM18PG471SN1D '              | 'SMLF'     | 'IND'    | 'TMP_QCX8PG471000'(!)      = ''              | ''                 | 'CX8PG471000'              |'L0603'| 'BLM18PG471SN1D '              | 'DISCRETE' | 'EMI FILTER BLM18PG471SN1D(470,1000MA)'         | 'CHIP'         | ''          | ''   | ''          
 'BLM18PG471SN1D '              | 'SMLF'     | 'EMPTY'  | 'TMP_QCX8PG471000'(!)      = ''              | ''                 | 'CX8PG471000'              |'L0603'| 'NA'                           | 'IO'       | 'EMI FILTER BLM18PG471SN1D(470,1000MA)'         | 'CHIP'         | ''          | ''   | ''          
 'MI1206K601R-10'               | 'SMLF'     | 'IND'    | 'TMP_QCX0K601R000'(!)      = 'Non-Preferred' | 'End of Life'      | 'CX0K601R000'              |'L1206_EOL'| 'MI1206K601R-10 '              | 'DISCRETE' | 'EMI FILTER MI1206K601R-10 (600,1.5A)'          | 'CHIP'         | ''          | ''   | ''          
 'MI1206K601R-10'               | 'SMLF'     | 'EMPTY'  | 'TMP_QCX0K601R000'(!)      = 'Non-Preferred' | 'End of Life'      | 'CX0K601R000'              |'L1206_EOL'| 'NA'                           | 'IO'       | 'EMI FILTER MI1206K601R-10 (600,1.5A)'          | 'CHIP'         | ''          | ''   | ''          
 'CDRH2D11NP-4R7NC'             | 'SMLF'     | 'IND'    | 'TMP_QCV-4705TZ02'(!)      = ''              | ''                 | 'CV-4705TZ02'              |'L_CDRH2D11NP'| 'CDRH2D11NP-4R7NC '            | 'DISCRETE' | 'IND SMD 4.7U 30% 0.5A(CDRH2D11NP-4R7NC)'       | 'CHIP'         | ''          | ''   | ''          
 'CDRH2D11NP-4R7NC'             | 'SMLF'     | 'EMPTY'  | 'TMP_QCV-4705TZ02'(!)      = ''              | ''                 | 'CV-4705TZ02'              |'L_CDRH2D11NP'| 'NA'                           | 'IO'       | 'IND SMD 4.7U 30% 0.5A(CDRH2D11NP-4R7NC)'       | 'CHIP'         | ''          | ''   | ''          
 'BRC2016T100M'                 | 'SMLF'     | 'IND'    | 'TMP_QCV01005MZ02'(!)      = ''              | ''                 | 'CV01005MZ02'              |'L0806XA'| '10UH '                        | 'DISCRETE' | 'IND SMD 10UH +-20%,0.45A(BRC2016T100M)'        | 'CHIP'         | ''          | ''   | ''          
 'BRC2016T100M'                 | 'SMLF'     | 'EMPTY'  | 'TMP_QCV01005MZ02'(!)      = ''              | ''                 | 'CV01005MZ02'              |'L0806XA'| 'NA'                           | 'IO'       | 'IND SMD 10UH +-20%,0.45A(BRC2016T100M)'        | 'CHIP'         | ''          | ''   | ''          
 'CDRH3D23NP-4R7PC'             | 'SMLF'     | 'IND'    | 'TMP_QCV-4713TZ00'(!)      = ''              | ''                 | 'CV-4713TZ00'              |'L_CDRH3D11-HP_H99'| 'CDRH3D23NP-4R7PC'             | 'DISCRETE' | 'IND SMD 4.7UH +-25% 1.3A(CDRH3D23NP-4R7P'      | 'CHIP'         | ''          | ''   | ''          
 'CDRH3D23NP-4R7PC'             | 'SMLF'     | 'EMPTY'  | 'TMP_QCV-4713TZ00'(!)      = ''              | ''                 | 'CV-4713TZ00'              |'L_CDRH3D11-HP_H99'| 'NA'                           | 'IO'       | 'IND SMD 4.7UH +-25% 1.3A(CDRH3D23NP-4R7P'      | 'CHIP'         | ''          | ''   | ''          
 'CDRH3D23NP-1R0PC'             | 'SMLF'     | 'IND'    | 'TMP_QCV-1028TZ00'(!)      = ''              | ''                 | 'CV-1028TZ00'              |'L_CDRH3D11-HP_H99'| 'CDRH3D23NP-1R0PC'             | 'DISCRETE' | 'IND SMD 1UH +-25% 2.8A(CDRH3D23NP-1R0PC)'      | 'CHIP'         | ''          | ''   | ''          
 'CDRH3D23NP-1R0PC'             | 'SMLF'     | 'EMPTY'  | 'TMP_QCV-1028TZ00'(!)      = ''              | ''                 | 'CV-1028TZ00'              |'L_CDRH3D11-HP_H99'| 'NA'                           | 'IO'       | 'IND SMD 1UH +-25% 2.8A(CDRH3D23NP-1R0PC)'      | 'CHIP'         | ''          | ''   | ''          
 'CDRH3D23NP-2R2PC'             | 'SMLF'     | 'IND'    | 'TMP_QCV-2218TZ00'(!)      = ''              | ''                 | 'CV-2218TZ00'              |'L_CDRH3D11-HP_H99'| 'CDRH3D23NP-2R2PC'             | 'DISCRETE' | 'IND SMD 2.2UH +-25% 1.8A(CDRH3D23NP-2R2P'      | 'CHIP'         | ''          | ''   | ''          
 'CDRH3D23NP-2R2PC'             | 'SMLF'     | 'EMPTY'  | 'TMP_QCV-2218TZ00'(!)      = ''              | ''                 | 'CV-2218TZ00'              |'L_CDRH3D11-HP_H99'| 'NA'                           | 'IO'       | 'IND SMD 2.2UH +-25% 1.8A(CDRH3D23NP-2R2P'      | 'CHIP'         | ''          | ''   | ''          
 '0.015UH'                      | 'SMLF'     | 'IND'    | 'TMP_QCVA1503JN51'(!)      = ''              | ''                 | 'CVA1503JN51'              |'L0402'| '0.015UH'                      | 'DISCRETE' | 'INDUCTOR CHIP 0.015U,+-5%,300MA,0402'          | 'CHIP'         | ''          | ''   | ''          
 '0.015UH'                      | 'SMLF'     | 'EMPTY'  | 'TMP_QCVA1503JN51'(!)      = ''              | ''                 | 'CVA1503JN51'              |'L0402'| 'NA'                           | 'IO'       | 'INDUCTOR CHIP 0.015U,+-5%,300MA,0402'          | 'CHIP'         | ''          | ''   | ''          
 '22NH'                         | 'SMLF'     | 'IND'    | 'TMP_QCVA2203JN02'(!)      = 'Potential'     | 'End of Life'      | 'CVA2203JN02'              |'L0402_EOL'| '22NH'                         | 'DISCRETE' | 'IND CHIP 22N +-5% 300MA,LQG15HS22NJ02D'        | 'CHIP'         | ''          | ''   | ''          
 '22NH'                         | 'SMLF'     | 'EMPTY'  | 'TMP_QCVA2203JN02'(!)      = 'Potential'     | 'End of Life'      | 'CVA2203JN02'              |'L0402_EOL'| 'NA'                           | 'IO'       | 'IND CHIP 22N +-5% 300MA,LQG15HS22NJ02D'        | 'CHIP'         | ''          | ''   | ''          
 'CDRH2D18/HP-4R7NC'            | 'SMLF'     | 'IND'    | 'TMP_QCV-4712TZ00'(!)      = ''              | ''                 | 'CV-4712TZ00'              |'L_CDRH2D11_H79'| 'CDRH2D18/HP-4R7NC '           | 'DISCRETE' | 'IND SMD 4.7U 30% 0.5A(CDRH2D11NP-4R7NC)'       | 'CHIP'         | ''          | ''   | ''          
 'CDRH2D18/HP-4R7NC'            | 'SMLF'     | 'EMPTY'  | 'TMP_QCV-4712TZ00'(!)      = ''              | ''                 | 'CV-4712TZ00'              |'L_CDRH2D11_H79'| 'NA'                           | 'IO'       | 'IND SMD 4.7U 30% 0.5A(CDRH2D11NP-4R7NC)'       | 'CHIP'         | ''          | ''   | ''          
 'BLM21PG600SN1D'               | 'SMLF'     | 'IND'    | 'TMP_QCX1PG600001'(!)      = 'End of Design' | 'Comp-Approve'     | 'CX1PG600001'              |'L0805'| 'BLM21PG600SN1D'               | 'DISCRETE' | 'EMI FILTER CHIP BLM21PG600SN1D(60,3A)'         | 'CHIP'         | ''          | ''   | ''          
 'BLM21PG600SN1D'               | 'SMLF'     | 'EMPTY'  | 'TMP_QCX1PG600001'(!)      = 'End of Design' | 'Comp-Approve'     | 'CX1PG600001'              |'L0805'| 'NA'                           | 'IO'       | 'EMI FILTER CHIP BLM21PG600SN1D(60,3A)'         | 'CHIP'         | ''          | ''   | ''          
 'EPL2010-102MLC'               | 'SMLF'     | 'IND'    | 'TMP_QCV-1010MZ02'(!)      = ''              | ''                 | 'CV-1010MZ02'              |'L_EPL2010'| 'EPL2010-102MLC'               | 'DISCRETE' | 'IND SMD 1U +-20% 1A(EPL2010-102MLC)'           | 'CHIP'         | ''          | ''   | ''          
 'EPL2010-102MLC'               | 'SMLF'     | 'EMPTY'  | 'TMP_QCV-1010MZ02'(!)      = ''              | ''                 | 'CV-1010MZ02'              |'L_EPL2010'| 'NA'                           | 'IO'       | 'IND SMD 1U +-20% 1A(EPL2010-102MLC)'           | 'CHIP'         | ''          | ''   | ''          
 '10UH'                         | 'SMLF'     | 'IND'    | 'TMP_QCV01002MZ01'(!)      = 'End of Design' | 'Comp-Approve'     | 'CV01002MZ01'              |'L0806'| '10UH'                         | 'DISCRETE' | 'IND SMD 10UH,+-20%,155MA(LB2016T100M)'         | 'CHIP'         | ''          | ''   | ''          
 '10UH'                         | 'SMLF'     | 'EMPTY'  | 'TMP_QCV01002MZ01'(!)      = 'End of Design' | 'Comp-Approve'     | 'CV01002MZ01'              |'L0806'| 'NA'                           | 'IO'       | 'IND SMD 10UH,+-20%,155MA(LB2016T100M)'         | 'CHIP'         | ''          | ''   | ''          
 '2700PH'                       | 'SMLF'     | 'IND'    | 'TMP_QCVB27F0TN00'(!)      = 'Potential'     | 'End of Life'      | 'CVB27F0TN00'              |'L0402_EOL'| '47UH'                         | 'DISCRETE' | 'IND CHIP 2700P +-0.2N 15A LQW15AN2N7C00D'      | 'CHIP'         | ''          | ''   | ''          
 '2700PH'                       | 'SMLF'     | 'EMPTY'  | 'TMP_QCVB27F0TN00'(!)      = 'Potential'     | 'End of Life'      | 'CVB27F0TN00'              |'L0402_EOL'| 'NA'                           | 'IO'       | 'IND CHIP 2700P +-0.2N 15A LQW15AN2N7C00D'      | 'CHIP'         | ''          | ''   | ''          
 '4.7UH'                        | 'SMLF'     | 'IND'    | 'TMP_QCV-4714MZ01'(!)      = ''              | ''                 | 'CV-4714MZ01'              |'L_VLF4014S'| '4.7UH'                        | 'DISCRETE' | 'IND SMD 4.7UH +-20% 1.4A VLF4014ST-4R7M1'      | 'CHIP'         | ''          | ''   | ''          
 '4.7UH'                        | 'SMLF'     | 'EMPTY'  | 'TMP_QCV-4714MZ01'(!)      = ''              | ''                 | 'CV-4714MZ01'              |'L_VLF4014S'| 'NA'                           | 'IO'       | 'IND SMD 4.7UH +-20% 1.4A VLF4014ST-4R7M1'      | 'CHIP'         | ''          | ''   | ''          
 '1UH'                          | 'SMLF'     | 'IND'    | 'TMP_QCV-1027TZ00'(!)      = ''              | ''                 | 'CV-1027TZ00'              |'L_VLF4014S'| '1UH'                          | 'DISCRETE' | 'IND SMD 1UH +-30% 2.7A VLF4014ST-1R0N2R3'      | 'CHIP'         | ''          | ''   | ''          
 '1UH'                          | 'SMLF'     | 'EMPTY'  | 'TMP_QCV-1027TZ00'(!)      = ''              | ''                 | 'CV-1027TZ00'              |'L_VLF4014S'| 'NA'                           | 'IO'       | 'IND SMD 1UH +-30% 2.7A VLF4014ST-1R0N2R3'      | 'CHIP'         | ''          | ''   | ''          
 '4.7UH'                        | 'SMLF'     | 'IND'    | 'TMP_QCV-4709MZ00'(!)      = ''              | ''                 | 'CV-4709MZ00'              |'L_VLF3012S'| '4.7UH'                        | 'DISCRETE' | 'IND SMD 4.7UH +-20% 0.91A VLF3012ST-4R7M'      | 'CHIP'         | ''          | ''   | ''          
 '4.7UH'                        | 'SMLF'     | 'EMPTY'  | 'TMP_QCV-4709MZ00'(!)      = ''              | ''                 | 'CV-4709MZ00'              |'L_VLF3012S'| 'NA'                           | 'IO'       | 'IND SMD 4.7UH +-20% 0.91A VLF3012ST-4R7M'      | 'CHIP'         | ''          | ''   | ''          
 '1UH'                          | 'SMLF'     | 'IND'    | 'TMP_QCV-1028TZ02'(!)      = ''              | 'End of Life'      | 'CV-1028TZ02'              |'L_SILM4025_EOL'| '1UH'                          | 'DISCRETE' | 'IND SMD 1UH +-25% 2.8A(SILM4025-1R0-F)'        | 'CHIP'         | ''          | ''   | ''          
 '1UH'                          | 'SMLF'     | 'EMPTY'  | 'TMP_QCV-1028TZ02'(!)      = ''              | 'End of Life'      | 'CV-1028TZ02'              |'L_SILM4025_EOL'| 'NA'                           | 'IO'       | 'IND SMD 1UH +-25% 2.8A(SILM4025-1R0-F)'        | 'CHIP'         | ''          | ''   | ''          
 '4.7UH'                        | 'SMLF'     | 'IND'    | 'TMP_QCV-4713TZ01'(!)      = ''              | 'End of Life'      | 'CV-4713TZ01'              |'L_SILM4025_EOL'| '4.7UH'                        | 'DISCRETE' | 'IND SMD 4.7UH +-25% 1.3A(SILM4025-4R7-F)'      | 'CHIP'         | ''          | ''   | ''          
 '4.7UH'                        | 'SMLF'     | 'EMPTY'  | 'TMP_QCV-4713TZ01'(!)      = ''              | 'End of Life'      | 'CV-4713TZ01'              |'L_SILM4025_EOL'| 'NA'                           | 'IO'       | 'IND SMD 4.7UH +-25% 1.3A(SILM4025-4R7-F)'      | 'CHIP'         | ''          | ''   | ''          
 '4.7UH'                        | 'SMLF'     | 'IND'    | 'TMP_QCV-4712TZ02'(!)      = ''              | 'End of Life'      | 'CV-4712TZ02'              |'L_SILM320A_EOL'| '4.7UH'                        | 'DISCRETE' | 'IND SMD 4.7UH +-25% 1.3A(SILM4025-4R7-F)'      | 'CHIP'         | ''          | ''   | ''          
 '4.7UH'                        | 'SMLF'     | 'EMPTY'  | 'TMP_QCV-4712TZ02'(!)      = ''              | 'End of Life'      | 'CV-4712TZ02'              |'L_SILM320A_EOL'| 'NA'                           | 'IO'       | 'IND SMD 4.7UH +-25% 1.3A(SILM4025-4R7-F)'      | 'CHIP'         | ''          | ''   | ''          
 '4.7UH'                        | 'SMLF'     | 'IND'    | 'TMP_QCV-4717MZ02'(!)      = 'End of Design' | 'Comp-Approve'     | 'CV-4717MZ02'              |'L_NR4018'| '4.7UH'                        | 'DISCRETE' | 'IND SMD 4.7UH +-20% 1700MA(NR4018T4R7M)'       | 'CHIP'         | ''          | ''   | ''          
 '4.7UH'                        | 'SMLF'     | 'EMPTY'  | 'TMP_QCV-4717MZ02'(!)      = 'End of Design' | 'Comp-Approve'     | 'CV-4717MZ02'              |'L_NR4018'| 'NA'                           | 'IO'       | 'IND SMD 4.7UH +-20% 1700MA(NR4018T4R7M)'       | 'CHIP'         | ''          | ''   | ''          
 '1UH'                          | 'SMLF'     | 'IND'    | 'TMP_QCV-1040TZ01'(!)      = ''              | ''                 | 'CV-1040TZ01'              |'L_NR4018'| '1UH'                          | 'DISCRETE' | 'IND SMD 1UH +-30% 4000MA(NR4018T1R0N)'         | 'CHIP'         | ''          | ''   | ''          
 '1UH'                          | 'SMLF'     | 'EMPTY'  | 'TMP_QCV-1040TZ01'(!)      = ''              | ''                 | 'CV-1040TZ01'              |'L_NR4018'| 'NA'                           | 'IO'       | 'IND SMD 1UH +-30% 4000MA(NR4018T1R0N)'         | 'CHIP'         | ''          | ''   | ''          
 'BLM18BD331SN1D'               | 'SMLF'     | 'IND'    | 'TMP_QCX8BD331004'(!)      = ''              | ''                 | 'CX8BD331004'              |'L0603'| 'BLM18BD331SN1D'               | 'DISCRETE' | 'EMI FILTER BLM18BD331SN1D(330,200MA)LF'        | 'CHIP'         | ''          | ''   | ''          
 'BLM18BD331SN1D'               | 'SMLF'     | 'EMPTY'  | 'TMP_QCX8BD331004'(!)      = ''              | ''                 | 'CX8BD331004'              |'L0603'| 'NA'                           | 'IO'       | 'EMI FILTER BLM18BD331SN1D(330,200MA)LF'        | 'CHIP'         | ''          | ''   | ''          
 '0.20UH'                       | 'SMLF'     | 'IND'    | 'TMP_QCV+20^0MZ01'(!)      = 'Non-Preferred' | 'End of Life'      | 'CV+20^0MZ01'              |'L_SIHH0606-R20M_EOL'| '0.20UH'                       | 'DISCRETE' | 'IND SMD 0.2UH,+-20%,35A(SIHC060675-R20M'       | 'CHIP'         | ''          | ''   | ''          
 '0.20UH'                       | 'SMLF'     | 'EMPTY'  | 'TMP_QCV+20^0MZ01'(!)      = 'Non-Preferred' | 'End of Life'      | 'CV+20^0MZ01'              |'L_SIHH0606-R20M_EOL'| 'NA'                           | 'IO'       | 'IND SMD 0.2UH,+-20%,35A(SIHC060675-R20M'       | 'CHIP'         | ''          | ''   | ''          
 '1.5UH'                        | 'SMLF'     | 'IND'    | 'TMP_QCV-15S0MZ15'(!)      = ''              | 'End of Life'      | 'CV-15S0MZ15'              |'L_MPL135_EOL'| '1.5UH'                        | 'DISCRETE' | 'IND SMD 1.5UH 20% 27A(MPL135-1R5)'             | 'CHIP'         | ''          | ''   | ''          
 '1.5UH'                        | 'SMLF'     | 'EMPTY'  | 'TMP_QCV-15S0MZ15'(!)      = ''              | 'End of Life'      | 'CV-15S0MZ15'              |'L_MPL135_EOL'| 'NA'                           | 'IO'       | 'IND SMD 1.5UH 20% 27A(MPL135-1R5)'             | 'CHIP'         | ''          | ''   | ''          
 '4.7UH'                        | 'SMLF'     | 'IND'    | 'TMP_QCV-47A0MZ04'(!)      = ''              | 'End of Life'      | 'CV-47A0MZ04'              |'L_MMD-06CZ_EOL'| '4.7UH'                        | 'DISCRETE' | 'IND SMD 4.7UH +-20%10A(MMD-06CZ-4R7M)'         | 'CHIP'         | ''          | ''   | ''          
 '4.7UH'                        | 'SMLF'     | 'EMPTY'  | 'TMP_QCV-47A0MZ04'(!)      = ''              | 'End of Life'      | 'CV-47A0MZ04'              |'L_MMD-06CZ_EOL'| 'NA'                           | 'IO'       | 'IND SMD 4.7UH +-20%10A(MMD-06CZ-4R7M)'         | 'CHIP'         | ''          | ''   | ''          
 '3.3UH'                        | 'SMLF'     | 'IND'    | 'TMP_QCV-3360MZ01'(!)      = ''              | ''                 | 'CV-3360MZ01'              |'L_MMD-06CZ'| '3.3UH'                        | 'DISCRETE' | 'IND SMD 3.3UH20%6A(MMD-06CZ-3R3M-V1W)'         | 'CHIP'         | ''          | ''   | ''          
 '3.3UH'                        | 'SMLF'     | 'EMPTY'  | 'TMP_QCV-3360MZ01'(!)      = ''              | ''                 | 'CV-3360MZ01'              |'L_MMD-06CZ'| 'NA'                           | 'IO'       | 'IND SMD 3.3UH20%6A(MMD-06CZ-3R3M-V1W)'         | 'CHIP'         | ''          | ''   | ''          
 '2.2UH'                        | 'SMLF'     | 'IND'    | 'TMP_QCV-2280MZ05'(!)      = ''              | ''                 | 'CV-2280MZ05'              |'L_MMD-06CZ'| '2.2UH'                        | 'DISCRETE' | 'IND SMD 2.2UH 20% 8A MMD-06CZ-2R2M-V1W'        | 'CHIP'         | ''          | ''   | ''          
 '2.2UH'                        | 'SMLF'     | 'EMPTY'  | 'TMP_QCV-2280MZ05'(!)      = ''              | ''                 | 'CV-2280MZ05'              |'L_MMD-06CZ'| 'NA'                           | 'IO'       | 'IND SMD 2.2UH 20% 8A MMD-06CZ-2R2M-V1W'        | 'CHIP'         | ''          | ''   | ''          
 '1UH'                          | 'SMLF'     | 'IND'    | 'TMP_QCV-10M0MZ02'(!)      = ''              | ''                 | 'CV-10M0MZ02'              |'L_MMD-06CZ'| '1UH'                          | 'DISCRETE' | 'IND SMD 1UH +-20%22A(MMD-06CZ-1R0M-V1W)'       | 'CHIP'         | ''          | ''   | ''          
 '1UH'                          | 'SMLF'     | 'EMPTY'  | 'TMP_QCV-10M0MZ02'(!)      = ''              | ''                 | 'CV-10M0MZ02'              |'L_MMD-06CZ'| 'NA'                           | 'IO'       | 'IND SMD 1UH +-20%22A(MMD-06CZ-1R0M-V1W)'       | 'CHIP'         | ''          | ''   | ''          
 'BK2125HS601'                  | 'SMLF'     | 'IND'    | 'CX5HS601007'(!)           = 'End of Design' | 'End of Life'      | 'CX5HS601007'              |'L0805_EOL'| 'BK2125HS601'                  | 'DISCRETE' | 'EMI FILTER CHIP BK2125HS601(200MA,600)'        | 'CHIP'         | ''          | ''   | ''          
 'BK2125HS601'                  | 'SMLF'     | 'EMPTY'  | 'CX5HS601007'(!)           = 'End of Design' | 'End of Life'      | 'CX5HS601007'              |'L0805_EOL'| 'NA'                           | 'IO'       | 'EMI FILTER CHIP BK2125HS601(200MA,600)'        | 'CHIP'         | ''          | ''   | ''          
 'MPZ1608S221AT'                | 'SMLF'     | 'IND'    | 'CX08S221001'(!)           = 'End of Design' | 'End of Life'      | 'CX08S221001'              |'L0603_EOL'| 'MPZ1608S221AT'                | 'DISCRETE' | 'EMI FILTER MPZ1608S221AT(220,2A,0.05)'         | 'CHIP'         | ''          | ''   | ''          
 'MPZ1608S221AT'                | 'SMLF'     | 'EMPTY'  | 'CX08S221001'(!)           = 'End of Design' | 'End of Life'      | 'CX08S221001'              |'L0603_EOL'| 'NA'                           | 'IO'       | 'EMI FILTER MPZ1608S221AT(220,2A,0.05)'         | 'CHIP'         | ''          | ''   | ''          
 '1.5UH'                        | 'SMLF'     | 'IND'    | 'CV-15I0MZ03'(!)           = ''              | ''                 | 'CV-15I0MZ03'              |'L_MMD-06CZ'| '1.5UH'                        | 'DISCRETE' | 'IND SMD 1.5UH 20% 18A(MMD-06CZ-1R5M-V1W)'      | 'CHIP'         | ''          | ''   | ''          
 '1.5UH'                        | 'SMLF'     | 'EMPTY'  | 'CV-15I0MZ03'(!)           = ''              | ''                 | 'CV-15I0MZ03'              |'L_MMD-06CZ'| 'NA'                           | 'IO'       | 'IND SMD 1.5UH 20% 18A(MMD-06CZ-1R5M-V1W)'      | 'CHIP'         | ''          | ''   | ''          
 'HCB1608K-181T15'              | 'SMLF'     | 'IND'    | 'CX000181016'(!)           = 'End of Design' | 'Comp-Approve'     | 'CX000181016'              |'L0603'| 'HCB1608K-181T15'              | 'DISCRETE' | 'EMI FILTER HCB1608KF-181T15(180,1.5A)'         | 'CHIP'         | ''          | ''   | ''          
 'HCB1608K-181T15'              | 'SMLF'     | 'EMPTY'  | 'CX000181016'(!)           = 'End of Design' | 'Comp-Approve'     | 'CX000181016'              |'L0603'| 'NA'                           | 'IO'       | 'EMI FILTER HCB1608KF-181T15(180,1.5A)'         | 'CHIP'         | ''          | ''   | ''          
 '4.7UH'                        | 'SMLF'     | 'IND'    | 'CV-4717MZ00'(!)           = ''              | ''                 | 'CV-4717MZ00'              |'L_MLPS5015'| '4.7UH'                        | 'DISCRETE' | 'IND SMD 4.7UH 20% 1.7A(MLPS-5015-4R7M-E)'      | 'CHIP'         | ''          | ''   | ''          
 '4.7UH'                        | 'SMLF'     | 'EMPTY'  | 'CV-4717MZ00'(!)           = ''              | ''                 | 'CV-4717MZ00'              |'L_MLPS5015'| 'NA'                           | 'IO'       | 'IND SMD 4.7UH 20% 1.7A(MLPS-5015-4R7M-E)'      | 'CHIP'         | ''          | ''   | ''          
 '1.0UH'                        | 'TH'       | 'IND'    | 'CV-10^0MD02'(!)           = ''              | ''                 | 'CV-10^0MD02'              |'L_TFHAH1311'| '1.0UH'                        | 'DISCRETE' | 'IND DIP 1.0UH +-20% 40A(TFHAH1311-1R0G-F'      | 'CHIP'         | ''          | ''   | ''          
 '1.0UH'                        | 'TH'       | 'EMPTY'  | 'CV-10^0MD02'(!)           = ''              | ''                 | 'CV-10^0MD02'              |'L_TFHAH1311'| 'NA'                           | 'IO'       | 'IND DIP 1.0UH +-20% 40A(TFHAH1311-1R0G-F'      | 'CHIP'         | ''          | ''   | ''          
 '1.2UH'                        | 'TH'       | 'IND'    | 'TMP-C_T2B_KC_0702_2'(!)   = ''              | ''                 | 'TMP-C_T2B_KC_0702_2'      |'L_TFHAH1311'| '1.2UH'                        | 'DISCRETE' | 'IND DIP 1.2UH +-20% 40A(TFHAH1311-1R2G-F)'     | 'CHIP'         | ''          | ''   | ''          
 '1.2UH'                        | 'TH'       | 'EMPTY'  | 'TMP-C_T2B_KC_0702_2'(!)   = ''              | ''                 | 'TMP-C_T2B_KC_0702_2'      |'L_TFHAH1311'| 'NA'                           | 'IO'       | 'IND DIP 1.2UH +-20% 40A(TFHAH1311-1R2G-F)'     | 'CHIP'         | ''          | ''   | ''          
 '470NH'                        | 'SMLF'     | 'IND'    | 'CV+47^0MZ02'(!)           = ''              | ''                 | 'CV+47^0MZ02'              |'L_HCB1190B'| '470NH'                        | 'DISCRETE' | 'IND SMD 470NH,+-20%,42A(HCB1190-471L)'         | 'CHIP'         | ''          | ''   | ''          
 '470NH'                        | 'SMLF'     | 'EMPTY'  | 'CV+47^0MZ02'(!)           = ''              | ''                 | 'CV+47^0MZ02'              |'L_HCB1190B'| 'NA'                           | 'IO'       | 'IND SMD 470NH,+-20%,42A(HCB1190-471L)'         | 'CHIP'         | ''          | ''   | ''          
 'TI321611U600'                 | 'SMLF'     | 'IND'    | 'CX11U600000'(!)           = 'End of Design' | 'End of Life'      | 'CX11U600000'              |'L1206_EOL'| 'TI321611U600'                 | 'DISCRETE' | 'EMI FILTER TI321611U600(60,3000MA)'            | 'CHIP'         | ''          | ''   | ''          
 'TI321611U600'                 | 'SMLF'     | 'EMPTY'  | 'CX11U600000'(!)           = 'End of Design' | 'End of Life'      | 'CX11U600000'              |'L1206_EOL'| 'NA'                           | 'IO'       | 'EMI FILTER TI321611U600(60,3000MA)'            | 'CHIP'         | ''          | ''   | ''          
 'MMZ1608S601A'                 | 'SMLF'     | 'IND'    | 'CX0S601A009'(!)           = 'End of Design' | 'Comp-Approve'     | 'CX0S601A009'              |'L0603'| 'MMZ1608S601A'                 | 'DISCRETE' | 'EMI FILTER MMZ1608S601A(400,100MHZ)EP'         | 'CHIP'         | ''          | ''   | ''          
 'MMZ1608S601A'                 | 'SMLF'     | 'EMPTY'  | 'CX0S601A009'(!)           = 'End of Design' | 'Comp-Approve'     | 'CX0S601A009'              |'L0603'| 'NA'                           | 'IO'       | 'EMI FILTER MMZ1608S601A(400,100MHZ)EP'         | 'CHIP'         | ''          | ''   | ''          
 'BLM18PG300SN1D'               | 'SMLF'     | 'IND'    | 'CX11P300000'(!)           = ''              | 'End of Life'      | 'CX11P300000'              |'L0603_EOL'| 'BLM18PG300SN1D'               | 'DISCRETE' | 'EMI FILTER CHIP BLM18PG300SN1D(1000MA)'        | 'CHIP'         | ''          | ''   | ''          
 'BLM18PG300SN1D'               | 'SMLF'     | 'EMPTY'  | 'CX11P300000'(!)           = ''              | 'End of Life'      | 'CX11P300000'              |'L0603_EOL'| 'NA'                           | 'IO'       | 'EMI FILTER CHIP BLM18PG300SN1D(1000MA)'        | 'CHIP'         | ''          | ''   | ''          
 '4.7UH'                        | 'SMLF'     | 'IND'    | 'CV-4701MN00'(!)           = 'End of Design' | 'Comp-Approve'     | 'CV-4701MN00'              |'L_MLZ2012'| '4.7UH      '                  | 'DISCRETE' | 'IND CHIP 4.7U,20%,80MA(MLZ2012E4R7MT)   '      | 'CHIP'         | ''          | ''   | '20100718'  
 '4.7UH'                        | 'SMLF'     | 'EMPTY'  | 'CV-4701MN00'(!)           = 'End of Design' | 'Comp-Approve'     | 'CV-4701MN00'              |'L_MLZ2012'| 'NA'                           | 'IO'       | 'IND CHIP 4.7U,20%,80MA(MLZ2012E4R7MT)   '      | 'CHIP'         | ''          | ''   | '20100718'  
 '4.7UH'                        | 'SMLF'     | 'IND'    | 'CV-4701TN01'(!)           = 'End of Design' | 'Comp-Approve'     | 'CV-4701TN01'              |'L0805'| '4.7UH      '                  | 'DISCRETE' | 'IND CHIP 4.7UH +-25%,80MA(MLZ2012E4R7PT)'      | 'CHIP'         | ''          | ''   | '20100718'  
 '4.7UH'                        | 'SMLF'     | 'EMPTY'  | 'CV-4701TN01'(!)           = 'End of Design' | 'Comp-Approve'     | 'CV-4701TN01'              |'L0805'| 'NA'                           | 'IO'       | 'IND CHIP 4.7UH +-25%,80MA(MLZ2012E4R7PT)'      | 'CHIP'         | ''          | ''   | '20100718'  
 'BLM18BB121S'                  | 'SMLF'     | 'IND'    | 'CX8BB121002'(!)           = ''              | ''                 | 'CX8BB121002'              |'L0603'| 'BLM18BB121S'                  | 'DISCRETE' | 'EMI FILTER BLM18BB121SN1D(120 0.2A)     '      | 'CHIP'         | ''          | ''   | '20100718'  
 'BLM18BB121S'                  | 'SMLF'     | 'EMPTY'  | 'CX8BB121002'(!)           = ''              | ''                 | 'CX8BB121002'              |'L0603'| 'NA'                           | 'IO'       | 'EMI FILTER BLM18BB121SN1D(120 0.2A)     '      | 'CHIP'         | ''          | ''   | '20100718'  
 '0.2UH'                        | 'SMLF'     | 'IND'    | 'CV+20^0MZ02'(!)           = 'End of Design' | 'End of Life'      | 'CV+20^0MZ02'              |'L_SFI060675R20MHF_EOL'| '0.2UH'                        | 'DISCRETE' | 'IND SMD 0.2UH,+-20%,35A(SFI060675-R20M)     '  | 'CHIP'         | ''          | ''   | '20100722'  
 '0.2UH'                        | 'SMLF'     | 'EMPTY'  | 'CV+20^0MZ02'(!)           = 'End of Design' | 'End of Life'      | 'CV+20^0MZ02'              |'L_SFI060675R20MHF_EOL'| 'NA'                           | 'IO'       | 'IND SMD 0.2UH,+-20%,35A(SFI060675-R20M)    '   | 'CHIP'         | ''          | ''   | '20100722'  
 '1.2UH'                        | 'THLF'     | 'IND'    | 'DC-12W0M000'(!)           = ''              | ''                 | 'DC-12W0M000'              |'LC_APL1310P1R2M'| '1.2UH'                        | 'DISCRETE' | 'CHOCK COIL(1.2UH+-20%31A)APL1310PQ-1R2M     '  | 'CHIP'         | ''          | ''   | '20100915'  
 '1.2UH'                        | 'THLF'     | 'EMPTY'  | 'DC-12W0M000'(!)           = ''              | ''                 | 'DC-12W0M000'              |'LC_APL1310P1R2M'| 'NA'                           | 'IO'       | 'CHOCK COIL(1.2UH+-20%31A)APL1310PQ-1R2M     '  | 'CHIP'         | ''          | ''   | '2010915'   
 '33NH'                         | 'SMLF'     | 'IND'    | 'CV+03G04N00'(!)           = ''              | 'End of Life'      | 'CV+03G04N00'              |'L0402XA_EOL'| '33NH'                         | 'DISCRETE' | 'IND CHIP 33NH,2%,400MA(HFC-1005C-33NG)    '    | 'CHIP'         | ''          | ''   | '20100805'  
 '33NH'                         | 'SMLF'     | 'EMPTY'  | 'CV+03G04N00'(!)           = ''              | 'End of Life'      | 'CV+03G04N00'              |'L0402XA_EOL'| 'NA'                           | 'IO'       | 'IND CHIP 33NH,2%,400MA(HFC-1005C-33NG)    '    | 'CHIP'         | ''          | ''   | '20100805'  
 'GB160808D500TT'               | 'SMLF'     | 'IND'    | 'CX08D500002'(!)           = 'End of Design' | 'Comp-Approve'     | 'CX08D500002'              |'L0603'| 'GB160808D500TT'               | 'DISCRETE' | 'EMI FILTER GB160808D500TT(50,600MA)    '       | 'CHIP'         | ''          | ''   | '20100814'  
 'GB160808D500TT'               | 'SMLF'     | 'EMPTY'  | 'CX08D500002'(!)           = 'End of Design' | 'Comp-Approve'     | 'CX08D500002'              |'L0603'| 'NA'                           | 'IO'       | 'EMI FILTER GB160808D500TT(50,600MA)    '       | 'CHIP'         | ''          | ''   | '20100814'  
 '300NH'                        | 'SMLF'     | 'IND'    | 'CV+30^0KZ01'(!)           = ''              | ''                 | 'CV+30^0KZ01'              |'L_HCB1290'| '300NH'                        | 'DISCRETE' | 'IND SMD 300NH +-10% 62A(HCB1290-301)    '      | 'CHIP'         | ''          | ''   | '20100816'  
 '300NH'                        | 'SMLF'     | 'EMPTY'  | 'CV+30^0KZ01'(!)           = ''              | ''                 | 'CV+30^0KZ01'              |'L_HCB1290'| 'NA'                           | 'IO'       | 'IND SMD 300NH +-10% 62A(HCB1290-301)    '      | 'CHIP'         | ''          | ''   | '20100816'  
 '1.5UH'                        | 'SMLF'     | 'IND'    | 'CV-1507MN00'(!)           = ''              | ''                 | 'CV-1507MN00'              |'L0805'| '1.5UH      '                  | 'DISCRETE' | 'IND CHIP 1.5UH 20%,0.7A(LQM21PN1R5MC0D)'       | 'CHIP'         | ''          | ''   | '20100908'  
 '1.5UH'                        | 'SMLF'     | 'EMPTY'  | 'CV-1507MN00'(!)           = ''              | ''                 | 'CV-1507MN00'              |'L0805'| 'NA'                           | 'IO'       | 'IND CHIP 1.5UH 20%,0.7A(LQM21PN1R5MC0D)'       | 'CHIP'         | ''          | ''   | '20100908'  
 'MPZ1608S601AT'                | 'SMLF'     | 'IND'    | 'CX08S601008'(!)           = 'End of Design' | 'End of Life'      | 'CX08S601008'              |'L0603_EOL'| 'MPZ1608S601AT '               | 'DISCRETE' | 'EMI FILTER MPZ1608S601AT(600,1A,0.15)    '     | 'CHIP'         | ''          | ''   | '20100909'  
 'MPZ1608S601AT'                | 'SMLF'     | 'EMPTY'  | 'CX08S601008'(!)           = 'End of Design' | 'End of Life'      | 'CX08S601008'              |'L0603_EOL'| 'NA'                           | 'IO'       | 'EMI FILTER MPZ1608S601AT(600,1A,0.15)    '     | 'CHIP'         | ''          | ''   | '20100909'  
 '0.6UH'                        | 'SMLF'     | 'IND'    | 'DC+60^0M000'(!)           = ''              | ''                 | 'DC+60^0M000'              |'LC_APL1108P'| '0.6UH'                        | 'DISCRETE' | 'CHOKE DIP 0.6UH +-20% 38A APL1108P-R60M    '   | 'CHIP'         | ''          | ''   | '20100819'  
 '0.6UH'                        | 'SMLF'     | 'EMPTY'  | 'DC+60^0M000'(!)           = ''              | ''                 | 'DC+60^0M000'              |'LC_APL1108P'| 'NA'                           | 'IO'       | 'CHOKE DIP 0.6UH +-20% 38A APL1108P-R60M    '   | 'CHIP'         | ''          | ''   | '20100819'  
 '1UH'                          | 'SMLF'     | 'IND'    | 'DC-10D0M002'(!)           = ''              | ''                 | 'DC-10D0M002'              |'LC_APL0806PC'| '1UH'                          | 'DISCRETE' | 'CHOKE 1UH+-20% 13A_APL0806PC-1R0M-C    '       | 'CHIP'         | ''          | ''   | '20100819'  
 '1UH'                          | 'SMLF'     | 'EMPTY'  | 'DC-10D0M002'(!)           = ''              | ''                 | 'DC-10D0M002'              |'LC_APL0806PC'| 'NA'                           | 'IO'       | 'CHOKE 1UH+-20% 13A_APL0806PC-1R0M-C    '       | 'CHIP'         | ''          | ''   | '20100819'  
 '1.2UH'                        | 'SMLF'     | 'IND'    | 'DC-12I0L002'(!)           = ''              | ''                 | 'DC-12I0L002'              |'LC_APL11T08PM'| '1.2UH'                        | 'DISCRETE' | 'CHOCK COIL 1.2UH +-15% 18A APL11T08PM    '     | 'CHIP'         | ''          | ''   | '20100819'  
 '1.2UH'                        | 'SMLF'     | 'EMPTY'  | 'DC-12I0L002'(!)           = ''              | ''                 | 'DC-12I0L002'              |'LC_APL11T08PM'| 'NA'                           | 'IO'       | 'CHOCK COIL 1.2UH +-15% 18A APL11T08PM    '     | 'CHIP'         | ''          | ''   | '20100819'  
 '3.3UH'                        | 'SMLF'     | 'IND'    | 'DC-33H0M000'(!)           = ''              | ''                 | 'DC-33H0M000'              |'LC_APL1109M'| '3.3UH'                        | 'DISCRETE' | 'CHOCK COIL 3.3UH +-20% 17A APL1109M-3R3M    '  | 'CHIP'         | ''          | ''   | '20100819'  
 '3.3UH'                        | 'SMLF'     | 'EMPTY'  | 'DC-33H0M000'(!)           = ''              | ''                 | 'DC-33H0M000'              |'LC_APL1109M'| 'NA'                           | 'IO'       | 'CHOCK COIL 3.3UH +-20% 17A APL1109M-3R3M    '  | 'CHIP'         | ''          | ''   | '20100819'  
 '5UH'                          | 'SMLF'     | 'IND'    | 'DC-50A0M002'(!)           = ''              | ''                 | 'DC-50A0M002'              |'LC_APL1108P6CQ'| '5UH'                          | 'DISCRETE' | 'CHOKE 5UH+-20% 10A_APL1108P6CQ-5R0M-C    '     | 'CHIP'         | ''          | ''   | '20100819'  
 '5UH'                          | 'SMLF'     | 'EMPTY'  | 'DC-50A0M002'(!)           = ''              | ''                 | 'DC-50A0M002'              |'LC_APL1108P6CQ'| 'NA'                           | 'IO'       | 'CHOKE 5UH+-20% 10A_APL1108P6CQ-5R0M-C    '     | 'CHIP'         | ''          | ''   | '20100819'  
 '4.7UH'                        | 'SMLF'     | 'IND'    | 'DC-47A0M001'(!)           = ''              | ''                 | 'DC-47A0M001'              |'LC_APL1108P-4R7M'| '4.7UH'                        | 'DISCRETE' | 'CHOCK COIL 4.7UH +-20% 10A APL1108P-4R7M    '  | 'CHIP'         | ''          | ''   | '20100920'  
 '4.7UH'                        | 'SMLF'     | 'EMPTY'  | 'DC-47A0M001'(!)           = ''              | ''                 | 'DC-47A0M001'              |'LC_APL1108P-4R7M'| 'NA'                           | 'IO'       | 'CHOCK COIL 4.7UH +-20% 10A APL1108P-4R7M    '  | 'CHIP'         | ''          | ''   | '20100920'  
 '3.3UH'                        | 'SMLF'     | 'IND'    | 'DC-33E0M000'(!)           = ''              | ''                 | 'DC-33E0M000'              |'LC_APL1108P-3R3M'| '3.3UH'                        | 'DISCRETE' | 'CHOCK COIL 3.3UH +-20% 14A APL1108P-3R3M    '  | 'CHIP'         | ''          | ''   | '20100920'  
 '3.3UH'                        | 'SMLF'     | 'EMPTY'  | 'DC-33E0M000'(!)           = ''              | ''                 | 'DC-33E0M000'              |'LC_APL1108P-3R3M'| 'NA'                           | 'IO'       | 'CHOCK COIL 3.3UH +-20% 14A APL1108P-3R3M    '  | 'CHIP'         | ''          | ''   | '20100920'  
 '4.7UH'                        | 'SMLF'     | 'IND'    | 'CV-47A0MZ10'(!)           = ''              | ''                 | 'CV-47A0MZ10'              |'L_PCMB104EXB'| '4.7UH'                        | 'DISCRETE' | 'IND SMD 4.7UH +-20% 10A(PCMB104E-4R7MS)'       | 'CHIP'         | ''          | ''   | '20110221'  
 '4.7UH'                        | 'SMLF'     | 'EMPTY'  | 'CV-47A0MZ10'(!)           = ''              | ''                 | 'CV-47A0MZ10'              |'L_PCMB104EXB'| 'NA'                           | 'IO'       | 'IND SMD 4.7UH +-20% 10A(PCMB104E-4R7MS)'       | 'CHIP'         | ''          | ''   | '20110221'  
 'BLM18EG221TN1D'               | 'SMLF'     | 'IND'    | 'CX8EG221003'(!)           = 'End of Design' | 'Comp-Approve'     | 'CX8EG221003'              |'L0603'| 'BLM18EG221TN1D '              | 'DISCRETE' | 'EMI FILTER BLM18EG221TN1D(220,1000MA)    '     | 'CHIP'         | ''          | ''   | '20100924'  
 'BLM18EG221TN1D'               | 'SMLF'     | 'EMPTY'  | 'CX8EG221003'(!)           = 'End of Design' | 'Comp-Approve'     | 'CX8EG221003'              |'L0603'| 'NA'                           | 'IO'       | 'EMI FILTER BLM18EG221TN1D(220,1000MA)    '     | 'CHIP'         | ''          | ''   | '20100924'  
 '1.5UH'                        | 'SMLF'     | 'IND'    | 'DC-15Q0M000'(!)           = ''              | ''                 | 'DC-15Q0M000'              |'LC_APL1108P-1R5M'| '1.5UH'                        | 'DISCRETE' | 'CHOCK COIL 1.5UH+-20%35A(APL1108P-1R5M)    '   | 'CHIP'         | ''          | ''   | '20100924'  
 '1.5UH'                        | 'SMLF'     | 'EMPTY'  | 'DC-15Q0M000'(!)           = ''              | ''                 | 'DC-15Q0M000'              |'LC_APL1108P-1R5M'| 'NA'                           | 'IO'       | 'CHOCK COIL 1.5UH+-20%35A(APL1108P-1R5M)    '   | 'CHIP'         | ''          | ''   | '20100924'  
 '2UH'                          | 'SMLF'     | 'IND'    | 'DC-20V0M000'(!)           = ''              | ''                 | 'DC-20V0M000'              |'LC_APL1108P-2R0M'| '2UH'                          | 'DISCRETE' | 'CHOCK COIL 2UH+-20% 35A(APL1108P-2R0M)     '   | 'CHIP'         | ''          | ''   | '20100924'  
 '2UH'                          | 'SMLF'     | 'EMPTY'  | 'DC-20V0M000'(!)           = ''              | ''                 | 'DC-20V0M000'              |'LC_APL1108P-2R0M'| 'NA'                           | 'IO'       | 'CHOCK COIL 2UH+-20% 35A(APL1108P-2R0M)     '   | 'CHIP'         | ''          | ''   | '20100924'  
 '0.68UH'                       | 'SMLF'     | 'IND'    | 'CV+68F5MZ03'(!)           = ''              | ''                 | 'CV+68F5MZ03'              |'L_MMD-06CZ'| '0.68UH'                       | 'DISCRETE' | 'IND SMD 0.68UH20%15.5A,MMD-06CZ-R68M-V1Q'      | 'CHIP'         | ''          | ''   | '20101004'  
 '0.68UH'                       | 'SMLF'     | 'EMPTY'  | 'CV+68F5MZ03'(!)           = ''              | ''                 | 'CV+68F5MZ03'              |'L_MMD-06CZ'| 'NA'                           | 'IO'       | 'IND SMD 0.68UH20%15.5A,MMD-06CZ-R68M-V1Q'      | 'CHIP'         | ''          | ''   | '20101004'  
 '4.7UH'                        | 'SMLF'     | 'IND'    | 'CV-4705MN06'(!)           = 'End of Design' | 'End of Life'      | 'CV-4705MN06'              |'L0805_H56_EOL'| '4.7UH'                        | 'DISCRETE' | 'IND CHIP 4.7UH+-20%450MA(GLF2012T4R7M)EP'      | 'CHIP'         | ''          | ''   | '20101005'  
 '4.7UH'                        | 'SMLF'     | 'EMPTY'  | 'CV-4705MN06'(!)           = 'End of Design' | 'End of Life'      | 'CV-4705MN06'              |'L0805_H56_EOL'| 'NA'                           | 'IO'       | 'IND CHIP 4.7UH+-20%450MA(GLF2012T4R7M)EP'      | 'CHIP'         | ''          | ''   | '20101005'  
 'TI160808U601'                 | 'SMLF'     | 'IND'    | 'CX08U601017'(!)           = 'End of Design' | 'End of Life'      | 'CX08U601017'              |'L0603_EOL'| 'TI160808U601'                 | 'DISCRETE' | 'EMI FILTER CHIP TI160808U601(600,200MA)'       | 'CHIP'         | ''          | ''   | '20101005'  
 'TI160808U601'                 | 'SMLF'     | 'EMPTY'  | 'CX08U601017'(!)           = 'End of Design' | 'End of Life'      | 'CX08U601017'              |'L0603_EOL'| 'NA'                           | 'IO'       | 'EMI FILTER CHIP TI160808U601(600,200MA)'       | 'CHIP'         | ''          | ''   | '20101005'  
 'MPZ2012S300A'                 | 'SMLF'     | 'IND'    | 'CX12S300003'(!)           = 'End of Design' | 'End of Life'      | 'CX12S300003'              |'L0805_EOL'| 'MPZ2012S300A'                 | 'DISCRETE' | 'EMI FIL CHIP MPZ2012S300AT (30 OHM,5A)EU'      | 'CHIP'         | ''          | ''   | '20101005'  
 'MPZ2012S300A'                 | 'SMLF'     | 'EMPTY'  | 'CX12S300003'(!)           = 'End of Design' | 'End of Life'      | 'CX12S300003'              |'L0805_EOL'| 'NA'                           | 'IO'       | 'EMI FIL CHIP MPZ2012S300AT (30 OHM,5A)EU'      | 'CHIP'         | ''          | ''   | '20101005'  
 'BLM41PG600SN1L'               | 'SMLF'     | 'IND'    | 'CX41PG60006'(!)           = ''              | ''                 | 'CX41PG60006'              |'L1806'| 'BLM41PG600SN1L'               | 'DISCRETE' | 'EMI FILTER CHIP BLM41PG600SN1L(60,6A)'         | 'CHIP'         | ''          | ''   | '20101005'  
 'BLM41PG600SN1L'               | 'SMLF'     | 'EMPTY'  | 'CX41PG60006'(!)           = ''              | ''                 | 'CX41PG60006'              |'L1806'| 'NA'                           | 'IO'       | 'EMI FILTER CHIP BLM41PG600SN1L(60,6A)'         | 'CHIP'         | ''          | ''   | '20101005'  
 '1.0UH'                        | 'THLF'     | 'IND'    | 'CV-10K0KD07'(!)           = 'End of Design' | 'End of Life'      | 'CV-10K0KD07'              |'LC14_P7-62_EOL'| '1.0UH'                        | 'DISCRETE' | 'INDUCTOR 1.0UH(+-10%,20A,HM00-01800LF)'        | 'CHIP'         | ''          | ''   | '20101008'  
 '1.0UH'                        | 'THLF'     | 'EMPTY'  | 'CV-10K0KD07'(!)           = 'End of Design' | 'End of Life'      | 'CV-10K0KD07'              |'LC14_P7-62_EOL'| 'NA'                           | 'IO'       | 'INDUCTOR 1.0UH(+-10%,20A,HM00-01800LF)'        | 'CHIP'         | ''          | ''   | '20101008'  
 '1.0UH'                        | 'THLF_SEL' | 'IND'    | 'CV-10K0KD07'(!)           = 'End of Design' | 'End of Life'      | 'CV-10K0KD07'              |'G_LC14_P7-62_EOL'| '1.0UH'                        | 'DISCRETE' | 'INDUCTOR 1.0UH(+-10%,20A,HM00-01800LF)'        | 'CHIP'         | ''          | ''   | '20101008'  
 '1.0UH'                        | 'THLF_SEL' | 'EMPTY'  | 'CV-10K0KD07'(!)           = 'End of Design' | 'End of Life'      | 'CV-10K0KD07'              |'G_LC14_P7-62_EOL'| 'NA'                           | 'IO'       | 'INDUCTOR 1.0UH(+-10%,20A,HM00-01800LF)'        | 'CHIP'         | ''          | ''   | '20101008'  
 '0.82UH'                       | 'SMLF'     | 'IND'    | 'CV+82W0MZ00'(!)           = ''              | ''                 | 'CV+82W0MZ00'              |'L_MMD12EZ'| '0.82UH'                       | 'DISCRETE' | 'IND SMD 0.82UH +-20%31A(MMD-12EZ-R82M)'        | 'CHIP'         | ''          | ''   | '20101025'  
 '0.82UH'                       | 'SMLF'     | 'EMPTY'  | 'CV+82W0MZ00'(!)           = ''              | ''                 | 'CV+82W0MZ00'              |'L_MMD12EZ'| 'NA'                           | 'IO'       | 'IND SMD 0.82UH +-20%31A(MMD-12EZ-R82M)'        | 'CHIP'         | ''          | ''   | '20101025'  
 '0.38UH'                       | 'SMLF'     | 'IND'    | 'CV+38^0EZ00'(!)           = ''              | ''                 | 'CV+38^0EZ00'              |'L_SIHH111109'| '0.38UH'                       | 'DISCRETE' | 'IND SMD 0.38U+-15% 42A(SIHH111109-R38L)'       | 'CHIP'         | ''          | ''   | '20101009'  
 '0.38UH'                       | 'SMLF'     | 'EMPTY'  | 'CV+38^0EZ00'(!)           = ''              | ''                 | 'CV+38^0EZ00'              |'L_SIHH111109'| 'NA'                           | 'IO'       | 'IND SMD 0.38U+-15% 42A(SIHH111109-R38L)'       | 'CHIP'         | ''          | ''   | '20101009'  
 '0.23UH'                       | 'SMLF'     | 'IND'    | 'CV+23^0MZ04'(!)           = ''              | ''                 | 'CV+23^0MZ04'              |'L_SIHH1309XA'| '0.23UH'                       | 'DISCRETE' | 'IND SMD 0.23U 20% 45A(SIHH1309-R23M-R30)'      | 'CHIP'         | ''          | ''   | '20101118'  
 '0.23UH'                       | 'SMLF'     | 'EMPTY'  | 'CV+23^0MZ04'(!)           = ''              | ''                 | 'CV+23^0MZ04'              |'L_SIHH1309XA'| 'NA'                           | 'IO'       | 'IND SMD 0.23U 20% 45A(SIHH1309-R23M-R30)'      | 'CHIP'         | ''          | ''   | '20101118'  
 '2.2UH'                        | 'SMLF'     | 'IND'    | 'CV-22X0MZ00'(!)           = ''              | ''                 | 'CV-22X0MZ00'              |'L_PCMC135T'| '2.2UH'                        | 'DISCRETE' | 'IND SMD 2.2UH 20% 32A(PCMC135T-2R2MF)'         | 'CHIP'         | ''          | ''   | '20110105'  
 '2.2UH'                        | 'SMLF'     | 'EMPTY'  | 'CV-22X0MZ00'(!)           = ''              | ''                 | 'CV-22X0MZ00'              |'L_PCMC135T'| 'NA'                           | 'IO'       | 'IND SMD 2.2UH 20% 32A(PCMC135T-2R2MF)'         | 'CHIP'         | ''          | ''   | '20110105'  
 '3.3UH'                        | 'SMLF'     | 'IND'    | 'CV-33X0MZ00'(!)           = ''              | ''                 | 'CV-33X0MZ00'              |'L_PCMC135T'| '3.3UH'                        | 'DISCRETE' | 'IND SMD 3.3UH 20% 32A(PCMC135T-3R3MF)'         | 'CHIP'         | ''          | ''   | '20110105'  
 '3.3UH'                        | 'SMLF'     | 'EMPTY'  | 'CV-33X0MZ00'(!)           = ''              | ''                 | 'CV-33X0MZ00'              |'L_PCMC135T'| 'NA'                           | 'IO'       | 'IND SMD 3.3UH 20% 32A(PCMC135T-3R3MF)'         | 'CHIP'         | ''          | ''   | '20110105'  
 'BLM21PG331SN1D'               | 'SMLF'     | 'IND'    | 'CX1PG331001'(!)           = 'End of Design' | 'Comp-Approve'     | 'CX1PG331001'              |'L0805'| 'BLM21PG331SN1D'               | 'DISCRETE' | 'EMI FIL CHIP BLM21PG331SN1D(330,1.5A)'         | 'CHIP'         | ''          | ''   | '20110114'  
 'BLM21PG331SN1D'               | 'SMLF'     | 'EMPTY'  | 'CX1PG331001'(!)           = 'End of Design' | 'Comp-Approve'     | 'CX1PG331001'              |'L0805'| 'NA'                           | 'IO'       | 'EMI FIL CHIP BLM21PG331SN1D(330,1.5A)'         | 'CHIP'         | ''          | ''   | '20110114'  
 '0.22U'                        | 'SMLF'     | 'IND'    | 'CV+22^0KZ02'(!)           = ''              | ''                 | 'CV+22^0KZ02'              |'L_SI2C100709'| '0.22U'                        | 'DISCRETE' | 'IND SMD 0.22U +-10% 45A(SI2C100709-R22K)'      | 'CHIP'         | ''          | ''   | '20110307'  
 '0.22U'                        | 'SMLF'     | 'EMPTY'  | 'CV+22^0KZ02'(!)           = ''              | ''                 | 'CV+22^0KZ02'              |'L_SI2C100709'| 'NA'                           | 'IO'       | 'IND SMD 0.22U +-10% 45A(SI2C100709-R22K)'      | 'CHIP'         | ''          | ''   | '20110307'  
 '0.27U'                        | 'SMLF'     | 'IND'    | 'CV+27^0KZ00'(!)           = ''              | ''                 | 'CV+27^0KZ00'              |'L_SI2C100709'| '0.27U'                        | 'DISCRETE' | 'IND SMD 0.27U +-10% 45A(SI2C100709-R27K)'      | 'CHIP'         | ''          | ''   | '20110307'  
 '0.27U'                        | 'SMLF'     | 'EMPTY'  | 'CV+27^0KZ00'(!)           = ''              | ''                 | 'CV+27^0KZ00'              |'L_SI2C100709'| 'NA'                           | 'IO'       | 'IND SMD 0.27U +-10% 45A(SI2C100709-R27K)'      | 'CHIP'         | ''          | ''   | '20110307'  
 '2.2UH'                        | 'SMLF'     | 'IND'    | 'CV-22X0MZ01'(!)           = ''              | ''                 | 'CV-22X0MZ01'              |'L_MMD12EZXA'| '2.2UH'                        | 'DISCRETE' | 'IND SMD 2.2UH 20% 32A(MMD-12EZ-2R2M-V1Q)'      | 'CHIP'         | ''          | ''   | '20110131'  
 '2.2UH'                        | 'SMLF'     | 'EMPTY'  | 'CV-22X0MZ01'(!)           = ''              | ''                 | 'CV-22X0MZ01'              |'L_MMD12EZXA'| 'NA'                           | 'IO'       | 'IND SMD 2.2UH 20% 32A(MMD-12EZ-2R2M-V1Q)'      | 'CHIP'         | ''          | ''   | '20110131'  
 '3.3UH'                        | 'SMLF'     | 'IND'    | 'CV-33X0MZ01'(!)           = ''              | ''                 | 'CV-33X0MZ01'              |'L_MMD12EZXA'| '3.3UH'                        | 'DISCRETE' | 'IND SMD 3.3UH 20% 32A(MMD-12EZ-3R3M-V1Q)'      | 'CHIP'         | ''          | ''   | '20110131'  
 '3.3UH'                        | 'SMLF'     | 'EMPTY'  | 'CV-33X0MZ01'(!)           = ''              | ''                 | 'CV-33X0MZ01'              |'L_MMD12EZXA'| 'NA'                           | 'IO'       | 'IND SMD 3.3UH 20% 32A(MMD-12EZ-3R3M-V1Q)'      | 'CHIP'         | ''          | ''   | '20110131'  
 '4.7UH'                        | 'SMLF'     | 'IND'    | 'CV-47S0MZ00'(!)           = ''              | ''                 | 'CV-47S0MZ00'              |'L_MMD12EZXA'| '4.7UH'                        | 'DISCRETE' | 'IND SMD 4.7UH 20% 27A(MMD-12EZ-4R7M-V1Q)'      | 'CHIP'         | ''          | ''   | '20110131'  
 '4.7UH'                        | 'SMLF'     | 'EMPTY'  | 'CV-47S0MZ00'(!)           = ''              | ''                 | 'CV-47S0MZ00'              |'L_MMD12EZXA'| 'NA'                           | 'IO'       | 'IND SMD 4.7UH 20% 27A(MMD-12EZ-4R7M-V1Q)'      | 'CHIP'         | ''          | ''   | '20110131'  
 '47NH'                         | 'SMLF'     | 'IND'    | 'CVA4703MZ00'(!)           = 'End of Design' | 'Comp-Approve'     | 'CVA4703MZ00'              |'L0805'| '47NH'                         | 'DISCRETE' | 'IND SMD 47N +-20% 300MA(MLF2012D47NMT)'        | 'CHIP'         | ''          | ''   | '20110208'  
 '47NH'                         | 'SMLF'     | 'EMPTY'  | 'CVA4703MZ00'(!)           = 'End of Design' | 'Comp-Approve'     | 'CVA4703MZ00'              |'L0805'| 'NA'                           | 'IO'       | 'IND SMD 47N +-20% 300MA(MLF2012D47NMT)'        | 'CHIP'         | ''          | ''   | '20110208'  
 '4.7UH'                        | 'SMLF'     | 'IND'    | 'CV-4702MN00'(!)           = ''              | ''                 | 'CV-4702MN00'              |'L0805'| '4.7UH'                        | 'DISCRETE' | 'IND CHIP 4.7UH+-20% 140MA(LB2012T4R7M)LF'      | 'CHIP'         | ''          | ''   | '20110219'  
 '4.7UH'                        | 'SMLF'     | 'EMPTY'  | 'CV-4702MN00'(!)           = ''              | ''                 | 'CV-4702MN00'              |'L0805'| 'NA'                           | 'IO'       | 'IND CHIP 4.7UH+-20% 140MA(LB2012T4R7M)LF'      | 'CHIP'         | ''          | ''   | '20110219'  
 '0.22UH'                       | 'SMLF'     | 'IND'    | 'CV+2290MZ00'(!)           = ''              | ''                 | 'CV+2290MZ00'              |'L_PCMB042T'| '0.22UH'                       | 'DISCRETE' | 'IND SMD 0.22UH +-20% 9A(PCMB042T-R22MS)'       | 'CHIP'         | ''          | ''   | '20110216'  
 '0.22UH'                       | 'SMLF'     | 'EMPTY'  | 'CV+2290MZ00'(!)           = ''              | ''                 | 'CV+2290MZ00'              |'L_PCMB042T'| 'NA'                           | 'IO'       | 'IND SMD 0.22UH +-20% 9A(PCMB042T-R22MS)'       | 'CHIP'         | ''          | ''   | '20110216'  
 '0.10UH'                       | 'SMLF'     | 'IND'    | 'CV+10X5MZ03'(!)           = ''              | ''                 | 'CV+10X5MZ03'              |'L_PCMC063T'| '0.10UH'                       | 'DISCRETE' | 'IND 0.10UH 32.5A,+-20%(PCMC063T-R10MN)'        | 'CHIP'         | ''          | ''   | '20110221'  
 '0.10UH'                       | 'SMLF'     | 'EMPTY'  | 'CV+10X5MZ03'(!)           = ''              | ''                 | 'CV+10X5MZ03'              |'L_PCMC063T'| 'NA'                           | 'IO'       | 'IND 0.10UH 32.5A,+-20%(PCMC063T-R10MN)'        | 'CHIP'         | ''          | ''   | '20110221'  
 '0.22UH'                       | 'SMLF'     | 'IND'    | 'CV+22N0MZ04'(!)           = ''              | ''                 | 'CV+22N0MZ04'              |'L_PCMC063T'| '0.22UH'                       | 'DISCRETE' | 'IND SMD 0.22UH 23A20%(PCMC063T-R22MN)'         | 'CHIP'         | ''          | ''   | '20110221'  
 '0.22UH'                       | 'SMLF'     | 'EMPTY'  | 'CV+22N0MZ04'(!)           = ''              | ''                 | 'CV+22N0MZ04'              |'L_PCMC063T'| 'NA'                           | 'IO'       | 'IND SMD 0.22UH 23A20%(PCMC063T-R22MN)'         | 'CHIP'         | ''          | ''   | '20110221'  
 '0.33UH'                       | 'SMLF'     | 'IND'    | 'CV+33K0MZ03'(!)           = ''              | ''                 | 'CV+33K0MZ03'              |'L_PCMC063T'| '0.33UH'                       | 'DISCRETE' | 'IND 0.33UH(20A +-20%,PCMC063T-R33MN)'          | 'CHIP'         | ''          | ''   | '20110221'  
 '0.33UH'                       | 'SMLF'     | 'EMPTY'  | 'CV+33K0MZ03'(!)           = ''              | ''                 | 'CV+33K0MZ03'              |'L_PCMC063T'| 'NA'                           | 'IO'       | 'IND 0.33UH(20A +-20%,PCMC063T-R33MN)'          | 'CHIP'         | ''          | ''   | '20110221'  
 '0.47UH'                       | 'SMLF'     | 'IND'    | 'CV+47R0MZ07'(!)           = ''              | ''                 | 'CV+47R0MZ07'              |'L_PCMC063T'| '0.47UH'                       | 'DISCRETE' | 'IND SMD 0.47UH 20% 26A(PCMC063T-R47MN)'        | 'CHIP'         | ''          | ''   | '20110221'  
 '0.47UH'                       | 'SMLF'     | 'EMPTY'  | 'CV+47R0MZ07'(!)           = ''              | ''                 | 'CV+47R0MZ07'              |'L_PCMC063T'| 'NA'                           | 'IO'       | 'IND SMD 0.47UH 20% 26A(PCMC063T-R47MN)'        | 'CHIP'         | ''          | ''   | '20110221'  
 '0.68UH'                       | 'SMLF'     | 'IND'    | 'CV+68F5MZ05'(!)           = ''              | ''                 | 'CV+68F5MZ05'              |'L_PCMC063T'| '0.68UH'                       | 'DISCRETE' | 'IND SMD 0.68U +-20%,15.5A PCMC063T-R68MN'      | 'CHIP'         | ''          | ''   | '20110221'  
 '0.68UH'                       | 'SMLF'     | 'EMPTY'  | 'CV+68F5MZ05'(!)           = ''              | ''                 | 'CV+68F5MZ05'              |'L_PCMC063T'| 'NA'                           | 'IO'       | 'IND SMD 0.68U +-20%,15.5A PCMC063T-R68MN'      | 'CHIP'         | ''          | ''   | '20110221'  
 '0.68UH'                       | 'SMLF'     | 'IND'    | 'CV+68Z0MZ02'(!)           = ''              | ''                 | 'CV+68Z0MZ02'              |'L_PCMC135T'| '0.68UH'                       | 'DISCRETE' | 'IND SMD 0.68UH +-20% 34A(PCMC135T-R68MF) '     | 'CHIP'         | ''          | ''   | '20110221'  
 '0.68UH'                       | 'SMLF'     | 'EMPTY'  | 'CV+68Z0MZ02'(!)           = ''              | ''                 | 'CV+68Z0MZ02'              |'L_PCMC135T'| 'NA'                           | 'IO'       | 'IND SMD 0.68UH +-20% 34A(PCMC135T-R68MF) '     | 'CHIP'         | ''          | ''   | '20110221'  
 '0.82UH'                       | 'SMLF'     | 'IND'    | 'CV+82D0MZ04'(!)           = ''              | ''                 | 'CV+82D0MZ04'              |'L_PCMC063T'| '0.82UH'                       | 'DISCRETE' | 'IND SMD 0.82UH +-20% 13A(PCMC063T-R82MN)'      | 'CHIP'         | ''          | ''   | '20110221'  
 '0.82UH'                       | 'SMLF'     | 'EMPTY'  | 'CV+82D0MZ04'(!)           = ''              | ''                 | 'CV+82D0MZ04'              |'L_PCMC063T'| 'NA'                           | 'IO'       | 'IND SMD 0.82UH +-20% 13A(PCMC063T-R82MN)'      | 'CHIP'         | ''          | ''   | '20110221'  
 '10UH'                         | 'SMLF'     | 'IND'    | 'CV01060MZ00'(!)           = ''              | ''                 | 'CV01060MZ00'              |'L_PCMB104TXB'| '10UH'                         | 'DISCRETE' | 'IND SMD 10UH +-20% 6A(PCMB104T-100MS)'         | 'CHIP'         | ''          | ''   | '20110221'  
 '10UH'                         | 'SMLF'     | 'EMPTY'  | 'CV01060MZ00'(!)           = ''              | ''                 | 'CV01060MZ00'              |'L_PCMB104TXB'| 'NA'                           | 'IO'       | 'IND SMD 10UH +-20% 6A(PCMB104T-100MS)'         | 'CHIP'         | ''          | ''   | '20110221'  
 '1UH'                          | 'SMLF'     | 'IND'    | 'CV-10B0MZ13'(!)           = ''              | ''                 | 'CV-10B0MZ13'              |'L_PCMC063T'| '1UH'                          | 'DISCRETE' | 'IND SMD 1UH 20%11A(PCMC063T-1R0MN)'            | 'CHIP'         | ''          | ''   | '20110221'  
 '1UH'                          | 'SMLF'     | 'EMPTY'  | 'CV-10B0MZ13'(!)           = ''              | ''                 | 'CV-10B0MZ13'              |'L_PCMC063T'| 'NA'                           | 'IO'       | 'IND SMD 1UH 20%11A(PCMC063T-1R0MN)'            | 'CHIP'         | ''          | ''   | '20110221'  
 '1.0UH'                        | 'SMLF'     | 'IND'    | 'CV-10I0MZ04'(!)           = ''              | ''                 | 'CV-10I0MZ04'              |'L_PCMB104TXA'| '1.0UH'                        | 'DISCRETE' | 'IND SMD 1.0UH +-20% 18A(PCMB104T-1R0MS)'       | 'CHIP'         | ''          | ''   | '20110221'  
 '1.0UH'                        | 'SMLF'     | 'EMPTY'  | 'CV-10I0MZ04'(!)           = ''              | ''                 | 'CV-10I0MZ04'              |'L_PCMB104TXA'| 'NA'                           | 'IO'       | 'IND SMD 1.0UH +-20% 18A(PCMB104T-1R0MS)'       | 'CHIP'         | ''          | ''   | '20110221'  
 '1UH'                          | 'SMLF'     | 'IND'    | 'CV-10U0MZ01'(!)           = ''              | ''                 | 'CV-10U0MZ01'              |'L_PCMC135T'| '1UH'                          | 'DISCRETE' | 'IND SMD 1UH +-20% 29A(PCMC135T-1R0MF)'         | 'CHIP'         | ''          | ''   | '20110221'  
 '1UH'                          | 'SMLF'     | 'EMPTY'  | 'CV-10U0MZ01'(!)           = ''              | ''                 | 'CV-10U0MZ01'              |'L_PCMC135T'| 'NA'                           | 'IO'       | 'IND SMD 1UH +-20% 29A(PCMC135T-1R0MF)'         | 'CHIP'         | ''          | ''   | '20110221'  
 '1.5UH'                        | 'SMLF'     | 'IND'    | 'CV-15G0MZ01'(!)           = ''              | ''                 | 'CV-15G0MZ01'              |'L_PCMB104TXA'| '1.5UH'                        | 'DISCRETE' | 'IND SMD 1.5UH +-20% 16A(PCMB104T-1R5MS)'       | 'CHIP'         | ''          | ''   | '20110221'  
 '1.5UH'                        | 'SMLF'     | 'EMPTY'  | 'CV-15G0MZ01'(!)           = ''              | ''                 | 'CV-15G0MZ01'              |'L_PCMB104TXA'| 'NA'                           | 'IO'       | 'IND SMD 1.5UH +-20% 16A(PCMB104T-1R5MS)'       | 'CHIP'         | ''          | ''   | '20110221'  
 '1.5UH'                        | 'SMLF'     | 'IND'    | 'CV-15I0MZ28'(!)           = ''              | ''                 | 'CV-15I0MZ28'              |'L_PCMC063T'| '1.5UH'                        | 'DISCRETE' | 'IND SMD 1.5UH+-20% 18A(PCMC063T-1R5MN)'        | 'CHIP'         | ''          | ''   | '20110221'  
 '1.5UH'                        | 'SMLF'     | 'EMPTY'  | 'CV-15I0MZ28'(!)           = ''              | ''                 | 'CV-15I0MZ28'              |'L_PCMC063T'| 'NA'                           | 'IO'       | 'IND SMD 1.5UH+-20% 18A(PCMC063T-1R5MN)'        | 'CHIP'         | ''          | ''   | '20110221'  
 '1.5UH'                        | 'SMLF'     | 'IND'    | 'CV-15N0MZ02'(!)           = ''              | ''                 | 'CV-15N0MZ02'              |'L_PCMC135T'| '1.5UH'                        | 'DISCRETE' | 'IND SMD 1.5UH 23A,+-20%(PCMC135T-1R5MF)'       | 'CHIP'         | ''          | ''   | '20110221'  
 '1.5UH'                        | 'SMLF'     | 'EMPTY'  | 'CV-15N0MZ02'(!)           = ''              | ''                 | 'CV-15N0MZ02'              |'L_PCMC135T'| 'NA'                           | 'IO'       | 'IND SMD 1.5UH 23A,+-20%(PCMC135T-1R5MF)'       | 'CHIP'         | ''          | ''   | '20110221'  
 '2.2UH'                        | 'SMLF'     | 'IND'    | 'CV-2230MZ03'(!)           = ''              | ''                 | 'CV-2230MZ03'              |'L_PCMB042T'| '2.2UH'                        | 'DISCRETE' | 'IND SMD 2.2UH +-20% 3A(PCMB042T-2R2MS)'        | 'CHIP'         | ''          | ''   | '20110221'  
 '2.2UH'                        | 'SMLF'     | 'EMPTY'  | 'CV-2230MZ03'(!)           = ''              | ''                 | 'CV-2230MZ03'              |'L_PCMB042T'| 'NA'                           | 'IO'       | 'IND SMD 2.2UH +-20% 3A(PCMB042T-2R2MS)'        | 'CHIP'         | ''          | ''   | '20110221'  
 '2.2UH'                        | 'SMLF'     | 'IND'    | 'CV-2280MZ15'(!)           = ''              | ''                 | 'CV-2280MZ15'              |'L_PCMC063T'| '2.2UH'                        | 'DISCRETE' | 'IND SMD 2.2UH +-20% 8A(PCMC063T-2R2MN)'        | 'CHIP'         | ''          | ''   | '20110221'  
 '2.2UH'                        | 'SMLF'     | 'EMPTY'  | 'CV-2280MZ15'(!)           = ''              | ''                 | 'CV-2280MZ15'              |'L_PCMC063T'| 'NA'                           | 'IO'       | 'IND SMD 2.2UH +-20% 8A(PCMC063T-2R2MN)'        | 'CHIP'         | ''          | ''   | '20110221'  
 '2.2UH'                        | 'SMLF'     | 'IND'    | 'CV-22C0MZ02'(!)           = ''              | ''                 | 'CV-22C0MZ02'              |'L_PCMB104TXB'| '2.2UH'                        | 'DISCRETE' | 'IND SMD 2.2UH+-20%12A(PCMB104T-2R2MN)'         | 'CHIP'         | ''          | ''   | '20110221'  
 '2.2UH'                        | 'SMLF'     | 'EMPTY'  | 'CV-22C0MZ02'(!)           = ''              | ''                 | 'CV-22C0MZ02'              |'L_PCMB104TXB'| 'NA'                           | 'IO'       | 'IND SMD 2.2UH+-20%12A(PCMB104T-2R2MN)'         | 'CHIP'         | ''          | ''   | '20110221'  
 '3.3UH'                        | 'SMLF'     | 'IND'    | 'CV-33B0MZ01'(!)           = ''              | ''                 | 'CV-33B0MZ01'              |'L_PCMB104TXB'| '3.3UH'                        | 'DISCRETE' | 'IND 3.3UH 11A +-20%(PCMB104E-3R3MS)'           | 'CHIP'         | ''          | ''   | '20110221'  
 '3.3UH'                        | 'SMLF'     | 'EMPTY'  | 'CV-33B0MZ01'(!)           = ''              | ''                 | 'CV-33B0MZ01'              |'L_PCMB104TXB'| 'NA'                           | 'IO'       | 'IND 3.3UH 11A +-20%(PCMB104E-3R3MS)'           | 'CHIP'         | ''          | ''   | '20110221'  
 '4.7UH'                        | 'SMLF'     | 'IND'    | 'CV-4755MZ12'(!)           = ''              | ''                 | 'CV-4755MZ12'              |'L_PCMC063T'| '4.7UH'                        | 'DISCRETE' | 'IND SMD 4.7U20%5.5A(PCMC063T-4R7MN)'           | 'CHIP'         | ''          | ''   | '20110221'  
 '4.7UH'                        | 'SMLF'     | 'EMPTY'  | 'CV-4755MZ12'(!)           = ''              | ''                 | 'CV-4755MZ12'              |'L_PCMC063T'| 'NA'                           | 'IO'       | 'IND SMD 4.7U20%5.5A(PCMC063T-4R7MN)'           | 'CHIP'         | ''          | ''   | '20110221'  
 '6.8UH'                        | 'SMLF'     | 'IND'    | 'CV-6845MZ05'(!)           = ''              | ''                 | 'CV-6845MZ05'              |'L_PCMC063T'| '6.8UH'                        | 'DISCRETE' | 'IND SMD 6.8UH +-20%,4.5A(PCMC063T-6R8MN)'      | 'CHIP'         | ''          | ''   | '20110221'  
 '6.8UH'                        | 'SMLF'     | 'EMPTY'  | 'CV-6845MZ05'(!)           = ''              | ''                 | 'CV-6845MZ05'              |'L_PCMC063T'| 'NA'                           | 'IO'       | 'IND SMD 6.8UH +-20%,4.5A(PCMC063T-6R8MN)'      | 'CHIP'         | ''          | ''   | '20110221'  
 '6.8UH'                        | 'SMLF'     | 'IND'    | 'CV-6865MZ02'(!)           = ''              | ''                 | 'CV-6865MZ02'              |'L_PCMB104TXB'| '6.8UH'                        | 'DISCRETE' | 'IND SMD 6.8UH +-20% 6.5A PCMB104T-6R8MS'       | 'CHIP'         | ''          | ''   | '20110221'  
 '6.8UH'                        | 'SMLF'     | 'EMPTY'  | 'CV-6865MZ02'(!)           = ''              | ''                 | 'CV-6865MZ02'              |'L_PCMB104TXB'| 'NA'                           | 'IO'       | 'IND SMD 6.8UH +-20% 6.5A PCMB104T-6R8MS'       | 'CHIP'         | ''          | ''   | '20110221'  
 '0.22UH'                       | 'SMLF'     | 'IND'    | 'TMP_TU1_KC_0303_2'(!)     = ''              | ''                 | 'TMP_TU1_KC_0303_2'        |'L_SI2C120609'| '0.22UH'                       | 'DISCRETE' | 'IND SMD 0.22UH +-10% 55A(SI2C120609-R22K-R27)' | 'CHIP'         | ''          | ''   | '20110303'  
 '0.22UH'                       | 'SMLF'     | 'EMPTY'  | 'TMP_TU1_KC_0303_2'(!)     = ''              | ''                 | 'TMP_TU1_KC_0303_2'        |'L_SI2C120609'| 'NA'                           | 'IO'       | 'IND SMD 0.22UH +-10% 55A(SI2C120609-R22K-R27)' | 'CHIP'         | ''          | ''   | '20110303'  
 '0.32UH'                       | 'SMLF'     | 'IND'    | 'CV+32^0KZ01'(!)           = ''              | ''                 | 'CV+32^0KZ01'              |'L_SI2C100709'| '0.32UH'                       | 'DISCRETE' | 'IND SMD 0.32U +-10% 35A(SI2C100709-R32K)'      | 'CHIP'         | ''          | ''   | '20110315'  
 '0.32UH'                       | 'SMLF'     | 'EMPTY'  | 'CV+32^0KZ01'(!)           = ''              | ''                 | 'CV+32^0KZ01'              |'L_SI2C100709'| 'NA'                           | 'IO'       | 'IND SMD 0.32U +-10% 35A(SI2C100709-R32K)'      | 'CHIP'         | ''          | ''   | '20110315'  
 '0.23UH'                       | 'SMLF'     | 'IND'    | 'CV+23^0EZ08'(!)           = ''              | ''                 | 'CV+23^0EZ08'              |'L_HCB137590271'| '0.23UH'                       | 'DISCRETE' | 'IND SMD 0.23UH +-15% 60A (HCB137590-231)'      | 'CHIP'         | ''          | ''   | '20110315'  
 '0.23UH'                       | 'SMLF'     | 'EMPTY'  | 'CV+23^0EZ08'(!)           = ''              | ''                 | 'CV+23^0EZ08'              |'L_HCB137590271'| 'NA'                           | 'IO'       | 'IND SMD 0.23UH +-15% 60A (HCB137590-231)'      | 'CHIP'         | ''          | ''   | '20110315'  
 '2.7UH'                        | 'SMLF'     | 'IND'    | 'CV-2703KN01'(!)           = ''              | ''                 | 'CV-2703KN01'              |'L0805'| '2.7UH'                        | 'DISCRETE' | 'IND 2.7UH+-10% 30MA GMLI-201209-2R7K'          | 'CHIP'         | ''          | ''   | '20110329'  
 '2.7UH'                        | 'SMLF'     | 'EMPTY'  | 'CV-2703KN01'(!)           = ''              | ''                 | 'CV-2703KN01'              |'L0805'| 'NA'                           | 'IO'       | 'IND 2.7UH+-10% 30MA GMLI-201209-2R7K'          | 'CHIP'         | ''          | ''   | '20110329'  
 '1.5UH'                        | 'SMLF'     | 'IND'    | 'CV-15G0MZ03'(!)           = ''              | ''                 | 'CV-15G0MZ03'              |'L_PCMC104T'| '1.5UH'                        | 'DISCRETE' | 'IND SMD 1.5UH +-20% 16A(PCMC104T-1R5MN)'       | 'CHIP'         | ''          | ''   | '20110330'  
 '1.5UH'                        | 'SMLF'     | 'EMPTY'  | 'CV-15G0MZ03'(!)           = ''              | ''                 | 'CV-15G0MZ03'              |'L_PCMC104T'| 'NA'                           | 'IO'       | 'IND SMD 1.5UH +-20% 16A(PCMC104T-1R5MN)'       | 'CHIP'         | ''          | ''   | '20110330'  
 '250NH'                        | 'SMLF'     | 'IND'    | 'CV+25^0EZ00'(!)           = ''              | ''                 | 'CV+25^0EZ00'              |'L_HCB1190B'| '250NH'                        | 'DISCRETE' | 'IND SMD 250NH +-15% 42A(HCB1190-251L-F)'       | 'CHIP'         | ''          | ''   | '20110510'  
 '250NH'                        | 'SMLF'     | 'EMPTY'  | 'CV+25^0EZ00'(!)           = ''              | ''                 | 'CV+25^0EZ00'              |'L_HCB1190B'| 'NA'                           | 'IO'       | 'IND SMD 250NH +-15% 42A(HCB1190-251L-F)'       | 'CHIP'         | ''          | ''   | '20110510'  
 '0.38UH'                       | 'SMLF'     | 'IND'    | 'CV+38^0EZ01'(!)           = ''              | ''                 | 'CV+38^0EZ01'              |'L_HCB1190381LF'| '0.38UH'                       | 'DISCRETE' | 'IND SMD 0.38U 15% 45A(HCB1190-381L-F)'         | 'CHIP'         | ''          | ''   | '20110812'  
 '0.38UH'                       | 'SMLF'     | 'EMPTY'  | 'CV+38^0EZ01'(!)           = ''              | ''                 | 'CV+38^0EZ01'              |'L_HCB1190381LF'| 'NA'                           | 'IO'       | 'IND SMD 0.38U 15% 45A(HCB1190-381L-F)'         | 'CHIP'         | ''          | ''   | '20110812'  
 '1.0UH'                        | 'SMLF'     | 'IND'    | 'CV-1070MZ09'(!)           = ''              | ''                 | 'CV-1070MZ09'              |'L_PCMB042T'| '1.0UH'                        | 'DISCRETE' | 'IND SMD 1.0UH 20% 7A(PCMB042T-1R0MS)'          | 'CHIP'         | ''          | ''   | '20110923'  
 '1.0UH'                        | 'SMLF'     | 'EMPTY'  | 'CV-1070MZ09'(!)           = ''              | ''                 | 'CV-1070MZ09'              |'L_PCMB042T'| 'NA'                           | 'IO'       | 'IND SMD 1.0UH 20% 7A(PCMB042T-1R0MS)'          | 'CHIP'         | ''          | ''   | '20110923'  
 'FCM2012CF-121T06'             | 'SMLF'     | 'IND'    | 'CX000121307'(!)           = ''              | ''                 | 'CX000121307'              |'L0805'| 'FCM2012CF-121T06'             | 'DISCRETE' | 'EMI FILTER FCM2012CF-121T06(600MA)'            | 'CHIP'         | ''          | ''   | '2011/11/25'
 'FCM2012CF-121T06'             | 'SMLF'     | 'EMPTY'  | 'CX000121307'(!)           = ''              | ''                 | 'CX000121307'              |'L0805'| 'NA'                           | 'IO'       | 'EMI FILTER FCM2012CF-121T06(600MA)'            | 'CHIP'         | ''          | ''   | '2011/11/25'
 '0.25U/34.5A'                  | 'THLF'     | 'IND'    | 'DC+25^0K000'(!)           = ''              | ''                 | 'DC+25^0K000'              |'L_AI2C110510'| '0.25U/34.5A'                  | 'DISCRETE' | 'CHOKE 0.25U +-10% 34.5A AI2C110510-R25K'       | 'CHIP'         | ''          | ''   | '20111130'  
 '0.25U/34.5A'                  | 'THLF'     | 'EMPTY'  | 'DC+25^0K000'(!)           = ''              | ''                 | 'DC+25^0K000'              |'L_AI2C110510'| 'NA'                           | 'IO'       | 'CHOKE 0.25U +-10% 34.5A AI2C110510-R25K'       | 'CHIP'         | ''          | ''   | '20111130'  
 '0.25U/45A'                    | 'SMLF'     | 'IND'    | 'CV+25^0KZ00'(!)           = ''              | ''                 | 'CV+25^0KZ00'              |'L_SI2C100709'| '0.25U/45A'                    | 'DISCRETE' | 'IND SMD 0.25U +-10% 45A(SI2C100709-R25K)'      | 'CHIP'         | ''          | ''   | '20111130'  
 '0.25U/45A'                    | 'SMLF'     | 'EMPTY'  | 'CV+25^0KZ00'(!)           = ''              | ''                 | 'CV+25^0KZ00'              |'L_SI2C100709'| 'NA'                           | 'IO'       | 'IND SMD 0.25U +-10% 45A(SI2C100709-R25K)'      | 'CHIP'         | ''          | ''   | '20111130'  
 '1000/0.2A'                    | 'SMLF'     | 'IND'    | 'CX1AG102000'(!)           = ''              | ''                 | 'CX1AG102000'              |'L0805'| '1000/0.2A'                    | 'DISCRETE' | 'EMI FILTER BLM21AG102SN1D(1000,0.2A)'          | 'CHIP'         | ''          | ''   | '20111212'  
 '1000/0.2A'                    | 'SMLF'     | 'EMPTY'  | 'CX1AG102000'(!)           = ''              | ''                 | 'CX1AG102000'              |'L0805'| 'NA'                           | 'IO'       | 'EMI FILTER BLM21AG102SN1D(1000,0.2A)'          | 'CHIP'         | ''          | ''   | '20111212'  
 '3.3UH/2A'                     | 'SMLF'     | 'IND'    | 'CV-3320MZ04'(!)           = ''              | ''                 | 'CV-3320MZ04'              |'L_WQPC0403'| '3.3UH/2A'                     | 'DISCRETE' | 'IND SMD 3.3UH,+-20% 2A(WQPC0403)'              | 'CHIP'         | ''          | ''   | '20111214'  
 '3.3UH/2A'                     | 'SMLF'     | 'EMPTY'  | 'CV-3320MZ04'(!)           = ''              | ''                 | 'CV-3320MZ04'              |'L_WQPC0403'| 'NA'                           | 'IO'       | 'IND SMD 3.3UH,+-20% 2A(WQPC0403)'              | 'CHIP'         | ''          | ''   | '20111214'  
 '1UH/15.3A'                    | 'SMLF'     | 'IND'    | 'CV-10F3MZ00'(!)           = ''              | ''                 | 'CV-10F3MZ00'              |'L_SPM6550T'| '1UH/15.3A'                    | 'DISCRETE' | 'IND SMD 1UH 20% 15.3A(SPM6550T-1R0M100A)'      | 'CHIP'         | ''          | ''   | '20111215'  
 '1UH/15.3A'                    | 'SMLF'     | 'EMPTY'  | 'CV-10F3MZ00'(!)           = ''              | ''                 | 'CV-10F3MZ00'              |'L_SPM6550T'| 'NA'                           | 'IO'       | 'IND SMD 1UH 20% 15.3A(SPM6550T-1R0M100A)'      | 'CHIP'         | ''          | ''   | '20111215'  
 '4.7UH/1.7A'                   | 'SMLF'     | 'IND'    | 'CV-4717TZ00'(!)           = 'Non-Preferred' | 'End of Life'      | 'CV-4717TZ00'              |'L_SIL620_EOL'| '4.7UH/1.7A'                   | 'DISCRETE' | 'IND SMD 4.7UH+-30%,1.7A(SIL620-4R7)'           | 'CHIP'         | ''          | ''   | '20111219'  
 '4.7UH/1.7A'                   | 'SMLF'     | 'EMPTY'  | 'CV-4717TZ00'(!)           = 'Non-Preferred' | 'End of Life'      | 'CV-4717TZ00'              |'L_SIL620_EOL'| 'NA'                           | 'IO'       | 'IND SMD 4.7UH+-30%,1.7A(SIL620-4R7)'           | 'CHIP'         | ''          | ''   | '20111219'  
 '3.3UH/6.6A'                   | 'SMLF'     | 'IND'    | 'TMP_S4E_JHIH-RONG_1219_1'(!) = ''              | ''                 | 'TMP_S4E_JHIH-RONG_1219_1' |'L_CLF10040T'| '3.3UH/6.6A'                   | 'DISCRETE' | 'IND SMD 3.3UH 30%  6.6A(CLF10040T-3R3N)'       | 'CHIP'         | ''          | ''   | '20111219'  
 '3.3UH/6.6A'                   | 'SMLF'     | 'EMPTY'  | 'TMP_S4E_JHIH-RONG_1219_1'(!) = ''              | ''                 | 'TMP_S4E_JHIH-RONG_1219_1' |'L_CLF10040T'| 'NA'                           | 'IO'       | 'IND SMD 3.3UH 30%  6.6A(CLF10040T-3R3N)'       | 'CHIP'         | ''          | ''   | '20111219'  
 '800/8A'                       | 'SMLF'     | 'IND'    | 'CX0V801R000'(!)           = 'End of Design' | 'Comp-Approve'     | 'CX0V801R000'              |'L_HR2220V801R'| '800/8A'                       | 'DISCRETE' | 'EMI FILTER HR2220V801R-10 (800.8A)'            | 'CHIP'         | ''          | ''   | '20111220'  
 '800/8A'                       | 'SMLF'     | 'EMPTY'  | 'CX0V801R000'(!)           = 'End of Design' | 'Comp-Approve'     | 'CX0V801R000'              |'L_HR2220V801R'| 'NA'                           | 'IO'       | 'EMI FILTER HR2220V801R-10 (800.8A)'            | 'CHIP'         | ''          | ''   | '20111220'  
 '1.1UH/3.7A'                   | 'SMLF'     | 'IND'    | 'CV-1137TZ00'(!)           = ''              | 'End of Life'      | 'CV-1137TZ00'              |'L_SIL620_EOL'| '1.1UH/3.7A'                   | 'DISCRETE' | 'IND SMD 1.1UH +-30% 3.7A(SIL620-1R1)'          | 'CHIP'         | ''          | ''   | '20120105'  
 '1.1UH/3.7A'                   | 'SMLF'     | 'EMPTY'  | 'CV-1137TZ00'(!)           = ''              | 'End of Life'      | 'CV-1137TZ00'              |'L_SIL620_EOL'| 'NA'                           | 'IO'       | 'IND SMD 1.1UH +-30% 3.7A(SIL620-1R1)'          | 'CHIP'         | ''          | ''   | '20120105'  
 '0.1UH/35A'                    | 'SMLF'     | 'IND'    | 'CV+10^0MZ04'(!)           = 'Non-Preferred' | 'End of Life'      | 'CV+10^0MZ04'              |'L_SIHC060675R10MR23_EOL'| '0.1UH/35A'                    | 'DISCRETE' | 'IND SMD 0.1UH,+-20%,35A SIHC060675-R10M'       | 'CHIP'         | ''          | ''   | '20120112'  
 '0.1UH/35A'                    | 'SMLF'     | 'EMPTY'  | 'CV+10^0MZ04'(!)           = 'Non-Preferred' | 'End of Life'      | 'CV+10^0MZ04'              |'L_SIHC060675R10MR23_EOL'| 'NA'                           | 'IO'       | 'IND SMD 0.1UH,+-20%,35A SIHC060675-R10M'       | 'CHIP'         | ''          | ''   | '20120112'  
 '0.18UH/54A'                   | 'SMLF'     | 'IND'    | 'CV+18^0KZ01'(!)           = 'Non-Preferred' | 'End of Life'      | 'CV+18^0KZ01'              |'L_SL4330B_EOL'| '0.18UH/54A'                   | 'DISCRETE' | 'IND SMD 0.18UH +-10% 54A(SL4330B-R18KU)'       | 'CHIP'         | ''          | ''   | '20120112'  
 '0.18UH/54A'                   | 'SMLF'     | 'EMPTY'  | 'CV+18^0KZ01'(!)           = 'Non-Preferred' | 'End of Life'      | 'CV+18^0KZ01'              |'L_SL4330B_EOL'| 'NA'                           | 'IO'       | 'IND SMD 0.18UH +-10% 54A(SL4330B-R18KU)'       | 'CHIP'         | ''          | ''   | '20120112'  
 '1.5UH/18A'                    | 'SMLF'     | 'IND'    | 'CV-15I0MZ08'(!)           = 'End of Design' | 'Comp-Approve'     | 'CV-15I0MZ08'              |'L_MPT730'| '1.5UH/18A'                    | 'DISCRETE' | 'IND SMD 1.5UH+-20% 18A(MPT730-1R5M1IN)'        | 'CHIP'         | ''          | ''   | '20120112'  
 '1.5UH/18A'                    | 'SMLF'     | 'EMPTY'  | 'CV-15I0MZ08'(!)           = 'End of Design' | 'Comp-Approve'     | 'CV-15I0MZ08'              |'L_MPT730'| 'NA'                           | 'IO'       | 'IND SMD 1.5UH+-20% 18A(MPT730-1R5M1IN)'        | 'CHIP'         | ''          | ''   | '20120112'  
 '2.2UH/14A'                    | 'SMLF'     | 'IND'    | 'CV-22E0MZ15'(!)           = ''              | ''                 | 'CV-22E0MZ15'              |'L_PCMB104E'| '2.2UH/14A'                    | 'DISCRETE' | 'IND SMD 2.2UH +-20% 14A(PCMB104E-2R2MS)'       | 'CHIP'         | ''          | ''   | '20120118'  
 '2.2UH/14A'                    | 'SMLF'     | 'EMPTY'  | 'CV-22E0MZ15'(!)           = ''              | ''                 | 'CV-22E0MZ15'              |'L_PCMB104E'| 'NA'                           | 'IO'       | 'IND SMD 2.2UH +-20% 14A(PCMB104E-2R2MS)'       | 'CHIP'         | ''          | ''   | '20120118'  
 '220NH/60A'                    | 'SMLF'     | 'IND'    | 'CV+22^0MZ08'(!)           = ''              | ''                 | 'CV+22^0MZ08'              |'L_HCB117590'| '220NH/60A'                    | 'DISCRETE' | 'IND SMD 220NH 20% 60A(HCB117590-221G)'         | 'CHIP'         | ''          | ''   | '20120131'  
 '220NH/60A'                    | 'SMLF'     | 'EMPTY'  | 'CV+22^0MZ08'(!)           = ''              | ''                 | 'CV+22^0MZ08'              |'L_HCB117590'| 'NA'                           | 'IO'       | 'IND SMD 220NH 20% 60A(HCB117590-221G)'         | 'CHIP'         | ''          | ''   | '20120131'  
 '33UH/4.3A'                    | 'SMLF'     | 'IND'    | 'CV03343MZ00'(!)           = ''              | ''                 | 'CV03343MZ00'              |'L_MSCDRI127A'| '33UH/4.3A'                    | 'DISCRETE' | 'IND SMD 33UH 20% 4.3A (MSCDRI-127A-330M)'      | 'CHIP'         | ''          | ''   | '20120209'  
 '33UH/4.3A'                    | 'SMLF'     | 'EMPTY'  | 'CV03343MZ00'(!)           = ''              | ''                 | 'CV03343MZ00'              |'L_MSCDRI127A'| 'NA'                           | 'IO'       | 'IND SMD 33UH 20% 4.3A (MSCDRI-127A-330M)'      | 'CHIP'         | ''          | ''   | '20120209'  
 '4.7UH/12A'                    | 'SMLF'     | 'IND'    | 'CV-47C0MZ01'(!)           = ''              | ''                 | 'CV-47C0MZ01'              |'L_PCMC135TXA'| '4.7UH/12A'                    | 'DISCRETE' | 'IND SMD 4.7UH +-20% 12A(PCMC135T-4R7MF)'       | 'CHIP'         | ''          | ''   | '20120215'  
 '4.7UH/12A'                    | 'SMLF'     | 'EMPTY'  | 'CV-47C0MZ01'(!)           = ''              | ''                 | 'CV-47C0MZ01'              |'L_PCMC135TXA'| 'NA'                           | 'IO'       | 'IND SMD 4.7UH +-20% 12A(PCMC135T-4R7MF)'       | 'CHIP'         | ''          | ''   | '20120215'  
 '10UH/125MA'                   | 'SMLF'     | 'IND'    | 'CV01002MN03'(!)           = ''              | ''                 | 'CV01002MN03'              |'L0805_H56'| '10UH/125MA'                   | 'DISCRETE' | 'IND 10UH, 20%,125MA LBR2012T100M'              | 'CHIP'         | ''          | ''   | '20120221'  
 '10UH/125MA'                   | 'SMLF'     | 'EMPTY'  | 'CV01002MN03'(!)           = ''              | ''                 | 'CV01002MN03'              |'L0805_H56'| 'NA'                           | 'IO'       | 'IND 10UH, 20%,125MA LBR2012T100M'              | 'CHIP'         | ''          | ''   | '20120221'  
 '100UH/315MA'                  | 'SMLF'     | 'IND'    | 'CV11004MZ00'(!)           = ''              | ''                 | 'CV11004MZ00'              |'L_MNR-3015'| '100UH/315MA'                  | 'DISCRETE' | 'IND SMD 100UH 20% 315MA(MNR-3015-101M-E)'      | 'CHIP'         | ''          | ''   | '20120306'  
 '100UH/315MA'                  | 'SMLF'     | 'EMPTY'  | 'CV11004MZ00'(!)           = ''              | ''                 | 'CV11004MZ00'              |'L_MNR-3015'| 'NA'                           | 'IO'       | 'IND SMD 100UH 20% 315MA(MNR-3015-101M-E)'      | 'CHIP'         | ''          | ''   | '20120306'  
 '0.36UH/30A'                   | 'SMLF'     | 'IND'    | 'CV+18V0MZ04'(!)           = ''              | ''                 | 'CV+18V0MZ04'              |'L_ETQP4LR36'| '0.36UH/30A'                   | 'DISCRETE' | 'IND SMD 0.36UH +-20% 30A(ETQP4LR36WFC)'        | 'CHIP'         | ''          | ''   | '20120307'  
 '0.36UH/30A'                   | 'SMLF'     | 'EMPTY'  | 'CV+18V0MZ04'(!)           = ''              | ''                 | 'CV+18V0MZ04'              |'L_ETQP4LR36'| 'NA'                           | 'IO'       | 'IND SMD 0.36UH +-20% 30A(ETQP4LR36WFC)'        | 'CHIP'         | ''          | ''   | '20120307'  
 '0.36UH/28A'                   | 'SMLF'     | 'IND'    | 'CV+36T0MZ01'(!)           = ''              | ''                 | 'CV+36T0MZ01'              |'L_ETQP4LR36'| '0.36UH/28A'                   | 'DISCRETE' | 'IND SMD 0.36U +-20%,28A(ETQP4LR36AFC)'         | 'CHIP'         | ''          | ''   | '20120307'  
 '0.36UH/28A'                   | 'SMLF'     | 'EMPTY'  | 'CV+36T0MZ01'(!)           = ''              | ''                 | 'CV+36T0MZ01'              |'L_ETQP4LR36'| 'NA'                           | 'IO'       | 'IND SMD 0.36U +-20%,28A(ETQP4LR36AFC)'         | 'CHIP'         | ''          | ''   | '20120307'  
 '0.1UH/35A'                    | 'SMLF'     | 'IND'    | 'CV+10^0MZ05'(!)           = ''              | ''                 | 'CV+10^0MZ05'              |'L_MSI-600608'| '0.1UH/35A'                    | 'DISCRETE' | 'IND SMD 0.1UH +-20% 35A MSI-600608-R10M'       | 'CHIP'         | ''          | ''   | '20120314'  
 '0.1UH/35A'                    | 'SMLF'     | 'EMPTY'  | 'CV+10^0MZ05'(!)           = ''              | ''                 | 'CV+10^0MZ05'              |'L_MSI-600608'| 'NA'                           | 'IO'       | 'IND SMD 0.1UH +-20% 35A MSI-600608-R10M'       | 'CHIP'         | ''          | ''   | '20120314'  
 '0.2UH/35A'                    | 'SMLF'     | 'IND'    | 'CV+20^0MZ04'(!)           = ''              | ''                 | 'CV+20^0MZ04'              |'L_MSI-600608'| '0.2UH/35A'                    | 'DISCRETE' | 'IND SMD 0.2UH +-20% 35A(MSI-600608-R20M'       | 'CHIP'         | ''          | ''   | '20120314'  
 '0.2UH/35A'                    | 'SMLF'     | 'EMPTY'  | 'CV+20^0MZ04'(!)           = ''              | ''                 | 'CV+20^0MZ04'              |'L_MSI-600608'| 'NA'                           | 'IO'       | 'IND SMD 0.2UH +-20% 35A(MSI-600608-R20M'       | 'CHIP'         | ''          | ''   | '20120314'  
 '0.1UH/18A'                    | 'SMLF'     | 'IND'    | 'TMP_T2L_KC_0316_1'(!)     = ''              | ''                 | 'TMP_T2L_KC_0316_1'        |'L_SIFH040406'| '0.1UH/18A'                    | 'DISCRETE' | 'IND SMD 0.1UH.+-20%18A(SIFH040406-R10M'        | 'CHIP'         | ''          | ''   | '20120316'  
 '0.1UH/18A'                    | 'SMLF'     | 'EMPTY'  | 'TMP_T2L_KC_0316_1'(!)     = ''              | ''                 | 'TMP_T2L_KC_0316_1'        |'L_SIFH040406'| 'NA'                           | 'IO'       | 'IND SMD 0.1UH.+-20%18A(SIFH040406-R10M'        | 'CHIP'         | ''          | ''   | '20120316'  
 '0.1UH/20A'                    | 'SMLF'     | 'IND'    | 'TMP_T2L_KC_0316_2'(!)     = ''              | ''                 | 'TMP_T2L_KC_0316_2'        |'L_IUT0406'| '0.1UH/20A'                    | 'DISCRETE' | 'IND SMD 0.1UH.+-20%20A(IUT0406-R10M'           | 'CHIP'         | ''          | ''   | '20120316'  
 '0.1UH/20A'                    | 'SMLF'     | 'EMPTY'  | 'TMP_T2L_KC_0316_2'(!)     = ''              | ''                 | 'TMP_T2L_KC_0316_2'        |'L_IUT0406'| 'NA'                           | 'IO'       | 'IND SMD 0.1UH.+-20%20A(IUT0406-R10M'           | 'CHIP'         | ''          | ''   | '20120316'  
 '0.1UH/12A'                    | 'SMLF'     | 'IND'    | 'TMP_T2L_KC_0319_1'(!)     = ''              | ''                 | 'TMP_T2L_KC_0319_1'        |'L_PCMB042T'| '0.1UH/12A'                    | 'DISCRETE' | 'IND SMD 0.1UH +-20% 12A(PCMB042T-R10MS)'       | 'CHIP'         | ''          | ''   | '20120319'  
 '0.1UH/12A'                    | 'SMLF'     | 'EMPTY'  | 'TMP_T2L_KC_0319_1'(!)     = ''              | ''                 | 'TMP_T2L_KC_0319_1'        |'L_PCMB042T'| 'NA'                           | 'IO'       | 'IND SMD 0.1UH +-20% 12A(PCMB042T-R10MS)'       | 'CHIP'         | ''          | ''   | '20120319'  
 '0.215UH/40A'                  | 'SMLF'     | 'IND'    | 'CV+21^0MZ03'(!)           = ''              | ''                 | 'CV+21^0MZ03'              |'L_HCB1065'| '0.215UH/40A'                  | 'DISCRETE' | 'IND SMD 0.215UH +-20% 40A(HCB1065-211)'        | 'CHIP'         | ''          | ''   | '20120320'  
 '0.215UH/40A'                  | 'SMLF'     | 'EMPTY'  | 'CV+21^0MZ03'(!)           = ''              | ''                 | 'CV+21^0MZ03'              |'L_HCB1065'| 'NA'                           | 'IO'       | 'IND SMD 0.215UH +-20% 40A(HCB1065-211)'        | 'CHIP'         | ''          | ''   | '20120320'  
 '3.3UH/2.15A'                  | 'SMLF'     | 'IND'    | 'CV-3322MZ02'(!)           = ''              | ''                 | 'CV-3322MZ02'              |'L_MSCD43XA'| '3.3UH/2.15A'                  | 'DISCRETE' | 'IND SMD 3.3UH +-20% 2.15A MSCD-43-3R3M-F'      | 'CHIP'         | ''          | ''   | '20120322'  
 '3.3UH/2.15A'                  | 'SMLF'     | 'EMPTY'  | 'CV-3322MZ02'(!)           = ''              | ''                 | 'CV-3322MZ02'              |'L_MSCD43XA'| 'NA'                           | 'IO'       | 'IND SMD 3.3UH +-20% 2.15A MSCD-43-3R3M-F'      | 'CHIP'         | ''          | ''   | '20120322'  
 '6.8UH/11A'                    | 'SMLF'     | 'IND'    | 'CV-68B0MZ00'(!)           = ''              | ''                 | 'CV-68B0MZ00'              |'L_MMD12EZXA'| '6.8UH/11A'                    | 'DISCRETE' | 'IND SMD 6.8UH +-20% 11A(MMD-12EZ-6R8M-V1'      | 'CHIP'         | ''          | ''   | '20120325'  
 '6.8UH/11A'                    | 'SMLF'     | 'EMPTY'  | 'CV-68B0MZ00'(!)           = ''              | ''                 | 'CV-68B0MZ00'              |'L_MMD12EZXA'| 'NA'                           | 'IO'       | 'IND SMD 6.8UH +-20% 11A(MMD-12EZ-6R8M-V1'      | 'CHIP'         | ''          | ''   | '20120325'  
 '330/2.5A'                     | 'SMLF'     | 'IND'    | 'CX12S331000'(!)           = 'End of Design' | 'End of Life'      | 'CX12S331000'              |'L0805_EOL'| '330/2.5A'                     | 'DISCRETE' | 'EMI FILTER MPZ2012S331AT(330,2.5A,0805)'       | 'CHIP'         | ''          | ''   | '20120323'  
 '330/2.5A'                     | 'SMLF'     | 'EMPTY'  | 'CX12S331000'(!)           = 'End of Design' | 'End of Life'      | 'CX12S331000'              |'L0805_EOL'| 'NA'                           | 'IO'       | 'EMI FILTER MPZ2012S331AT(330,2.5A,0805)'       | 'CHIP'         | ''          | ''   | '20120323'  
 '100UH/1.25A'                  | 'SMLF'     | 'IND'    | 'CV11013MZ00'(!)           = ''              | ''                 | 'CV11013MZ00'              |'L_MSCDRI104RXA'| '330/2.5A'                     | 'DISCRETE' | 'IND SMD 100UH 20% 1.25A MSCDRI-104R-101M'      | 'CHIP'         | ''          | ''   | '20120326'  
 '100UH/1.25A'                  | 'SMLF'     | 'EMPTY'  | 'CV11013MZ00'(!)           = ''              | ''                 | 'CV11013MZ00'              |'L_MSCDRI104RXA'| 'NA'                           | 'IO'       | 'IND SMD 100UH 20% 1.25A MSCDRI-104R-101M'      | 'CHIP'         | ''          | ''   | '20120326'  
 '1UH/32A'                      | 'SMLF'     | 'IND'    | 'CV-10X0MZ00'(!)           = ''              | ''                 | 'CV-10X0MZ00'              |'L_MMD12FD'| '1UH/32A'                      | 'DISCRETE' | 'IND SMD 1UH +-20% 32A MMD-12FD-1R0M-V1Q'       | 'CHIP'         | ''          | ''   | '20120326'  
 '1UH/32A'                      | 'SMLF'     | 'EMPTY'  | 'CV-10X0MZ00'(!)           = ''              | ''                 | 'CV-10X0MZ00'              |'L_MMD12FD'| 'NA'                           | 'IO'       | 'IND SMD 1UH +-20% 32A MMD-12FD-1R0M-V1Q'       | 'CHIP'         | ''          | ''   | '20120326'  
 '0.1UH/12A'                    | 'SMLF'     | 'IND'    | 'CV+10C0MZ00'(!)           = ''              | ''                 | 'CV+10C0MZ00'              |'L_PCMB042T'| '0.1UH/12A'                    | 'DISCRETE' | 'IND SMD 0.1UH +-20% 12A(PCMB042T-R10MS)'       | 'CHIP'         | ''          | ''   | '20120326'  
 '0.1UH/12A'                    | 'SMLF'     | 'EMPTY'  | 'CV+10C0MZ00'(!)           = ''              | ''                 | 'CV+10C0MZ00'              |'L_PCMB042T'| 'NA'                           | 'IO'       | 'IND SMD 0.1UH +-20% 12A(PCMB042T-R10MS)'       | 'CHIP'         | ''          | ''   | '20120326'  
 '350NH/65A'                    | 'SMLF'     | 'IND'    | 'CV+35^0MZ00'(!)           = ''              | ''                 | 'CV+35^0MZ00'              |'L_HCBD101195451G'| '350NH/65A'                    | 'DISCRETE' | 'IND SMD 350NH +-20% 65A(HCBD101195-351G)'      | 'CHIP'         | ''          | ''   | '20120405'  
 '350NH/65A'                    | 'SMLF'     | 'EMPTY'  | 'CV+35^0MZ00'(!)           = ''              | ''                 | 'CV+35^0MZ00'              |'L_HCBD101195451G'| 'NA'                           | 'IO'       | 'IND SMD 350NH +-20% 65A(HCBD101195-351G)'      | 'CHIP'         | ''          | ''   | '20120405'  
 '1.0UH/3A'                     | 'SMLF'     | 'IND'    | 'CV-1030TN01'(!)           = ''              | ''                 | 'CV-1030TN01'              | 'L_DFE252012C'                    | '1.0UH/3A'                     | 'DISCRETE' | 'IND CHIP 1.0UH 30% 3A(1239AS-H-1R0N=P2)'       | 'CHIP'         | ''          | ''   | '20120405'  
 '1.0UH/3A'                     | 'SMLF'     | 'EMPTY'  | 'CV-1030TN01'(!)           = ''              | ''                 | 'CV-1030TN01'              | 'L_DFE252012C'                    | 'NA'                           | 'IO'       | 'IND CHIP 1.0UH 30% 3A(1239AS-H-1R0N=P2)'       | 'CHIP'         | ''          | ''   | '20120405'  
 '600/0.5A'                     | 'SMLF'     | 'IND'    | 'CX8AG601003'(!)           = ''              | ''                 | 'CX8AG601003'              |'L0603'| '600/0.5A'                     | 'DISCRETE' | 'EMI FILTER BLM18AG601SN1D(600.0.5A)'           | 'CHIP'         | ''          | ''   | '20120416'  
 '600/0.5A'                     | 'SMLF'     | 'EMPTY'  | 'CX8AG601003'(!)           = ''              | ''                 | 'CX8AG601003'              |'L0603'| 'NA'                           | 'IO'       | 'EMI FILTER BLM18AG601SN1D(600.0.5A)'           | 'CHIP'         | ''          | ''   | '20120416'  
 '1.0UH/1A'                     | 'SMLF'     | 'IND'    | 'CV-1010MZ07'(!)           = ''              | ''                 | 'CV-1010MZ07'              |'L1210'| '1.0UH/1A'                     | 'DISCRETE' | 'IND SMD 1U +-20% 1A(LQH32CN1R0M33L)1210'       | 'CHIP'         | ''          | ''   | '20120419'  
 '1.0UH/1A'                     | 'SMLF'     | 'EMPTY'  | 'CV-1010MZ07'(!)           = ''              | ''                 | 'CV-1010MZ07'              |'L1210'| 'NA'                           | 'IO'       | 'IND SMD 1U +-20% 1A(LQH32CN1R0M33L)1210'       | 'CHIP'         | ''          | ''   | '20120419'  
 '80/5A'                        | 'SMLF'     | 'IND'    | 'CX09U800004'(!)           = 'End of Design' | 'End of Life'      | 'CX09U800004'              |'L0805_EOL'| '80/5A'                        | 'DISCRETE' | 'EMI FILTER TI201209U800(80,5A)'                | 'CHIP'         | ''          | ''   | '20120424'  
 '80/5A'                        | 'SMLF'     | 'EMPTY'  | 'CX09U800004'(!)           = 'End of Design' | 'End of Life'      | 'CX09U800004'              |'L0805_EOL'| 'NA'                           | 'IO'       | 'EMI FILTER TI201209U800(80,5A)'                | 'CHIP'         | ''          | ''   | '20120424'  
 '47/300MA'                     | 'SMLF'     | 'IND'    | 'CX8BA470003'(!)           = 'End of Design' | 'Comp-Approve'     | 'CX8BA470003'              |'L0603'| '47/300MA'                     | 'DISCRETE' | 'EMI FITTER BLM18BA470SN1(47.300MA)'            | 'CHIP'         | ''          | ''   | '20120427'  
 '47/300MA'                     | 'SMLF'     | 'EMPTY'  | 'CX8BA470003'(!)           = 'End of Design' | 'Comp-Approve'     | 'CX8BA470003'              |'L0603'| 'NA'                           | 'IO'       | 'EMI FITTER BLM18BA470SN1(47.300MA)'            | 'CHIP'         | ''          | ''   | '20120427'  
 '0.32U/45A'                    | 'SMLF'     | 'IND'    | 'CV+32^0KZ03'(!)           = 'Non-Preferred' | 'End of Life'      | 'CV+32^0KZ03'              |'L_SIHH1309XA_EOL'| '0.32U/45A'                    | 'DISCRETE' | 'IND SMD 0.32U 10% 45A(SIHH1309-R32K)'          | 'CHIP'         | ''          | ''   | '20120502'  
 '0.32U/45A'                    | 'SMLF'     | 'EMPTY'  | 'CV+32^0KZ03'(!)           = 'Non-Preferred' | 'End of Life'      | 'CV+32^0KZ03'              |'L_SIHH1309XA_EOL'| 'NA'                           | 'IO'       | 'IND SMD 0.32U 10% 45A(SIHH1309-R32K)'          | 'CHIP'         | ''          | ''   | '20120502'  
 '0.1UH/16A'                    | 'SMLF'     | 'IND'    | 'CV+10G0MZ00'(!)           = 'Non-Preferred' | 'End of Life'      | 'CV+10G0MZ00'              |'L_SIFH040406_EOL'| '0.1UH/16A'                    | 'DISCRETE' | 'IND SMD 0.1UH 20%16A SIFH040406-R10M-R30'      | 'CHIP'         | ''          | ''   | '20120502'  
 '0.1UH/16A'                    | 'SMLF'     | 'EMPTY'  | 'CV+10G0MZ00'(!)           = 'Non-Preferred' | 'End of Life'      | 'CV+10G0MZ00'              |'L_SIFH040406_EOL'| 'NA'                           | 'IO'       | 'IND SMD 0.1UH 20%16A SIFH040406-R10M-R30'      | 'CHIP'         | ''          | ''   | '20120502'  
 '1.0U'                         | 'SMLF'     | 'IND'    | 'CV-1015MZ00'(!)           = ''              | ''                 | 'CV-1015MZ00'              |'L_CPL2512T'| '1.0U/1.5A'                    | 'DISCRETE' | 'IND SMD 1.0U +-20% 1.5A(CPL2512T1R0M)'         | 'CHIP'         | ''          | ''   | '20120531'  
 '1.0U'                         | 'SMLF'     | 'EMPTY'  | 'CV-1015MZ00'(!)           = ''              | ''                 | 'CV-1015MZ00'              |'L_CPL2512T'| 'NA'                           | 'IO'       | 'IND SMD 1.0U +-20% 1.5A(CPL2512T1R0M)'         | 'CHIP'         | ''          | ''   | '20120531'  
 '1.5U'                         | 'SMLF'     | 'IND'    | 'CV-1520TZ00'(!)           = ''              | ''                 | 'CV-1520TZ00'              |'L_VLS252012'| '1.5U/2A'                      | 'DISCRETE' | 'IND SMD 1.5U +-30% 2A(VLS252012T-1R5)'         | 'CHIP'         | ''          | ''   | '20120531'  
 '1.5U'                         | 'SMLF'     | 'EMPTY'  | 'CV-1520TZ00'(!)           = ''              | ''                 | 'CV-1520TZ00'              |'L_VLS252012'| 'NA'                           | 'IO'       | 'IND SMD 1.5U +-30% 2A(VLS252012T-1R5)'         | 'CHIP'         | ''          | ''   | '20120531'  
 '220/700MA'                    | 'SMLF'     | 'IND'    | 'CX5EG221008'(!)           = ''              | ''                 | 'CX5EG221008'              |'L0402'| '220/700MA'                    | 'DISCRETE' | 'EMI FILTER BLM15EG221SN1D(220,700MA)'          | 'CHIP'         | ''          | ''   | '20120531'  
 '220/700MA'                    | 'SMLF'     | 'EMPTY'  | 'CX5EG221008'(!)           = ''              | ''                 | 'CX5EG221008'              |'L0402'| 'NA'                           | 'IO'       | 'EMI FILTER BLM15EG221SN1D(220,700MA)'          | 'CHIP'         | ''          | ''   | '20120531'  
 '1.0UH'                        | 'SMLF'     | 'IND'    | 'CV-10^0MZ04'(!)           = ''              | ''                 | 'CV-10^0MZ04'              |'L_HCBD14311'| '1.0UH'                        | 'DISCRETE' | 'IND SMD 1.0UH +-20% 40A(HCBD141311-102)'       | 'CHIP'         | ''          | ''   | '20120605'  
 '1.0UH'                        | 'SMLF'     | 'EMPTY'  | 'CV-10^0MZ04'(!)           = ''              | ''                 | 'CV-10^0MZ04'              |'L_HCBD14311'| 'NA'                           | 'IO'       | 'IND SMD 1.0UH +-20% 40A(HCBD141311-102)'       | 'CHIP'         | ''          | ''   | '20120605'  
 '1.2UH'                        | 'SMLF'     | 'IND'    | 'CV-12X0MZ00'(!)           = ''              | ''                 | 'CV-12X0MZ00'              |'L_HCBD14311'| '1.2UH'                        | 'DISCRETE' | 'IND SMD 1.2UH +-20% 32A(HCBD141311-122)'       | 'CHIP'         | ''          | ''   | '20120605'  
 '1.2UH'                        | 'SMLF'     | 'EMPTY'  | 'CV-12X0MZ00'(!)           = ''              | ''                 | 'CV-12X0MZ00'              |'L_HCBD14311'| 'NA'                           | 'IO'       | 'IND SMD 1.2UH +-20% 32A(HCBD141311-122)'       | 'CHIP'         | ''          | ''   | '20120605'  
 '1.5UH'                        | 'SMLF'     | 'IND'    | 'CV-15Q0MZ00'(!)           = ''              | ''                 | 'CV-15Q0MZ00'              |'L_HCBD14311'| '1.5UH'                        | 'DISCRETE' | 'IND SMD 1.5UH +-20% 25A(HCBD141311-152)'       | 'CHIP'         | ''          | ''   | '20120605'  
 '1.5UH'                        | 'SMLF'     | 'EMPTY'  | 'CV-15Q0MZ00'(!)           = ''              | ''                 | 'CV-15Q0MZ00'              |'L_HCBD14311'| 'NA'                           | 'IO'       | 'IND SMD 1.5UH +-20% 25A(HCBD141311-152)'       | 'CHIP'         | ''          | ''   | '20120605'  
 '0.8UH'                        | 'SMLF'     | 'IND'    | 'CV+80^0MZ00'(!)           = ''              | ''                 | 'CV+80^0MZ00'              |'L_HCBD14311'| '0.8UH'                        | 'DISCRETE' | 'IND SMD 0.8UH +-20% 50A(HCBD141311-801)'       | 'CHIP'         | ''          | ''   | '20120605'  
 '0.8UH'                        | 'SMLF'     | 'EMPTY'  | 'CV+80^0MZ00'(!)           = ''              | ''                 | 'CV+80^0MZ00'              |'L_HCBD14311'| 'NA'                           | 'IO'       | 'IND SMD 0.8UH +-20% 50A(HCBD141311-801)'       | 'CHIP'         | ''          | ''   | '20120605'  
 '10UH'                         | 'SMLF'     | 'IND'    | 'CV01040MZ04'(!)           = ''              | ''                 | 'CV01040MZ04'              |'L_MMD-06CZXA'| '10UH'                         | 'DISCRETE' | 'IND SMD 10UH +-20%,4A(MMD-06CZ-100M-X2Q)'      | 'CHIP'         | ''          | ''   | '20120605'  
 '10UH'                         | 'SMLF'     | 'EMPTY'  | 'CV01040MZ04'(!)           = ''              | ''                 | 'CV01040MZ04'              |'L_MMD-06CZXA'| 'NA'                           | 'IO'       | 'IND SMD 10UH +-20%,4A(MMD-06CZ-100M-X2Q)'      | 'CHIP'         | ''          | ''   | '20120605'  
 '3.3UH'                        | 'SMLF'     | 'IND'    | 'CV-3322MZ09'(!)           = ''              | 'End of Life'      | 'CV-3322MZ09'              |'L_PIDE43-3R3_EOL'| '3.3UH'                        | 'DISCRETE' | 'IND SMD 3.3UH.20%.2.15A(PIDE43-3R3)'           | 'CHIP'         | ''          | ''   | '20120614'  
 '3.3UH'                        | 'SMLF'     | 'EMPTY'  | 'CV-3322MZ09'(!)           = ''              | 'End of Life'      | 'CV-3322MZ09'              |'L_PIDE43-3R3_EOL'| 'NA'                           | 'IO'       | 'IND SMD 3.3UH.20%.2.15A(PIDE43-3R3)'           | 'CHIP'         | ''          | ''   | '20120614'  
 'BLM21PG221SN1D'               | 'SMLF'     | 'IND'    | 'CX1PG221001'(!)           = 'End of Design' | 'Comp-Approve'     | 'CX1PG221001'              |'L0805'| 'BLM21PG221SN1D'               | 'DISCRETE' | 'EMI FILTER BLM21PG221SN1D(220.100M.2A)'        | 'CHIP'         | ''          | ''   | '20120619'  
 'BLM21PG221SN1D'               | 'SMLF'     | 'EMPTY'  | 'CX1PG221001'(!)           = 'End of Design' | 'Comp-Approve'     | 'CX1PG221001'              |'L0805'| 'NA'                           | 'IO'       | 'EMI FILTER BLM21PG221SN1D(220.100M.2A)'        | 'CHIP'         | ''          | ''   | '20120619'  
 '100UH'                        | 'SMLF'     | 'IND'    | 'CV11005MZ00'(!)           = ''              | ''                 | 'CV11005MZ00'              |'L_SIG4018L'| '100UH'                        | 'DISCRETE' | 'IND SMD 100UH 20% 0.45A(SIG4018L-101)'         | 'CHIP'         | ''          | ''   | '20120706'  
 '100UH'                        | 'SMLF'     | 'EMPTY'  | 'CV11005MZ00'(!)           = ''              | ''                 | 'CV11005MZ00'              |'L_SIG4018L'| 'NA'                           | 'IO'       | 'IND SMD 100UH 20% 0.45A(SIG4018L-101)'         | 'CHIP'         | ''          | ''   | '20120706'  
 '8.2NH'                        | 'SMLF'     | 'IND'    | 'CVB8203JN01'(!)           = ''              | ''                 | 'CVB8203JN01'              |'L0402'| '8.2NH'                        | 'DISCRETE' | 'IND CHIP 8.2N(+-5%,0.3A)LQG15HN8N2J02D'        | 'CHIP'         | ''          | ''   | '20120709'  
 '8.2NH'                        | 'SMLF'     | 'EMPTY'  | 'CVB8203JN01'(!)           = ''              | ''                 | 'CVB8203JN01'              |'L0402'| 'NA'                           | 'IO'       | 'IND CHIP 8.2N(+-5%,0.3A)LQG15HN8N2J02D'        | 'CHIP'         | ''          | ''   | '20120709'  
 '2.2NH'                        | 'SMLF'     | 'IND'    | 'CVB2205BN01'(!)           = 'End of Design' | 'Comp-Release Qty' | 'CVB2205BN01'              |'L0201'| '2.2NH'                        | 'DISCRETE' | 'IND CHIP 2.2NH(0.1N,440MA)LQP03TN2N2B00D'      | 'CHIP'         | ''          | ''   | '20120709'  
 '2.2NH'                        | 'SMLF'     | 'EMPTY'  | 'CVB2205BN01'(!)           = 'End of Design' | 'Comp-Release Qty' | 'CVB2205BN01'              |'L0201'| 'NA'                           | 'IO'       | 'IND CHIP 2.2NH(0.1N,440MA)LQP03TN2N2B00D'      | 'CHIP'         | ''          | ''   | '20120709'  
 '8.2NH'                        | 'SMLF'     | 'IND'    | 'CVB8203JN03'(!)           = ''              | ''                 | 'CVB8203JN03'              |'L0402'| '8.2NH'                        | 'DISCRETE' | 'IND CHIP 8.2NH,+-5%,300MA,0402(LQG15HS8)'      | 'CHIP'         | ''          | ''   | '20120709'  
 '8.2NH'                        | 'SMLF'     | 'EMPTY'  | 'CVB8203JN03'(!)           = ''              | ''                 | 'CVB8203JN03'              |'L0402'| 'NA'                           | 'IO'       | 'IND CHIP 8.2NH,+-5%,300MA,0402(LQG15HS8)'      | 'CHIP'         | ''          | ''   | '20120709'  
 '100UH'                        | 'SMLF'     | 'IND'    | 'CV11007MZ00'(!)           = ''              | ''                 | 'CV11007MZ00'              |'L_MNR-4030'| '100UH'                        | 'DISCRETE' | 'IND SMD 100UH +-20% 0.65A(MNR-4030-101M)'      | 'CHIP'         | ''          | ''   | '20120710'  
 '100UH'                        | 'SMLF'     | 'EMPTY'  | 'CV11007MZ00'(!)           = ''              | ''                 | 'CV11007MZ00'              |'L_MNR-4030'| 'NA'                           | 'IO'       | 'IND SMD 100UH +-20% 0.65A(MNR-4030-101M)'      | 'CHIP'         | ''          | ''   | '20120710'  
 '3.3UH'                        | 'SMLF'     | 'IND'    | 'CV-3335MZ01'(!)           = ''              | ''                 | 'CV-3335MZ01'              |'L_MSCDRI6D38'| '3.3UH'                        | 'DISCRETE' | 'IND SMD 3.3U 20% 3.5A MSCDRI-6D38-3R3M'        | 'CHIP'         | ''          | ''   | '20120714'  
 '3.3UH'                        | 'SMLF'     | 'EMPTY'  | 'CV-3335MZ01'(!)           = ''              | ''                 | 'CV-3335MZ01'              |'L_MSCDRI6D38'| 'NA'                           | 'IO'       | 'IND SMD 3.3U 20% 3.5A MSCDRI-6D38-3R3M'        | 'CHIP'         | ''          | ''   | '20120714'  
 '0.47UH'                       | 'SMLF'     | 'IND'    | 'CV+47^0KZ01'(!)           = ''              | ''                 | 'CV+47^0KZ01'              |'L_HCUV138795'| '0.47UH'                       | 'DISCRETE' | 'IND SMD 0.47UH +-10% 41A(HCUV138795-471B'      | 'CHIP'         | ''          | ''   | '20120714'  
 '0.47UH'                       | 'SMLF'     | 'EMPTY'  | 'CV+47^0KZ01'(!)           = ''              | ''                 | 'CV+47^0KZ01'              |'L_HCUV138795'| 'NA'                           | 'IO'       | 'IND SMD 0.47UH +-10% 41A(HCUV138795-471B'      | 'CHIP'         | ''          | ''   | '20120714'  
 '0.27UH'                       | 'SMLF'     | 'IND'    | 'CV+27^0KZ02'(!)           = ''              | ''                 | 'CV+27^0KZ02'              |'L_HCUV138795'| '0.27UH'                       | 'DISCRETE' | 'IND SMD 0.27UH +-10% 72A (HCUV138795-271B)'    | 'CHIP'         | ''          | ''   | '20120714'  
 '0.27UH'                       | 'SMLF'     | 'EMPTY'  | 'CV+27^0KZ02'(!)           = ''              | ''                 | 'CV+27^0KZ02'              |'L_HCUV138795'| 'NA'                           | 'IO'       | 'IND SMD 0.27UH +-10% 72A (HCUV138795-271B)'    | 'CHIP'         | ''          | ''   | '20120714'  
 '0.47UH'                       | 'SMLF'     | 'IND'    | 'CV+47^0KZ00'(!)           = ''              | ''                 | 'CV+47^0KZ00'              |'L_HCB138590'| '0.47UH'                       | 'DISCRETE' | 'IND SMD 0.47UH +-10% 38A (HCB138590-471B)'     | 'CHIP'         | ''          | ''   | '20120714'  
 '0.47UH'                       | 'SMLF'     | 'EMPTY'  | 'CV+47^0KZ00'(!)           = ''              | ''                 | 'CV+47^0KZ00'              |'L_HCB138590'| 'NA'                           | 'IO'       | 'IND SMD 0.47UH +-10% 38A (HCB138590-471B)'     | 'CHIP'         | ''          | ''   | '20120714'  
 '0.27UH'                       | 'SMLF'     | 'IND'    | 'CV+27^0KZ01'(!)           = ''              | ''                 | 'CV+27^0KZ01'              |'L_HCB138590'| '0.27UH'                       | 'DISCRETE' | 'IND SMD 0.27UH +-10% 72A(HCB138590-271B)'      | 'CHIP'         | ''          | ''   | '20120714'  
 '0.27UH'                       | 'SMLF'     | 'EMPTY'  | 'CV+27^0KZ01'(!)           = ''              | ''                 | 'CV+27^0KZ01'              |'L_HCB138590'| 'NA'                           | 'IO'       | 'IND SMD 0.27UH +-10% 72A(HCB138590-271B))'     | 'CHIP'         | ''          | ''   | '20120714'  
 'MPZ2012S101AT(100ohm)'        | 'SMLF'     | 'IND'    | 'CX12S101001'(!)           = 'End of Design' | 'End of Life'      | 'CX12S101001'              |'L0805_EOL'| 'MPZ2012S101AT(100ohm)'        | 'DISCRETE' | 'EMI FIL CHIP MPZ2012S101AT(100.4A)L-F'         | 'CHIP'         | ''          | ''   | '20120714'  
 'MPZ2012S101AT(100ohm)'        | 'SMLF'     | 'EMPTY'  | 'CX12S101001'(!)           = 'End of Design' | 'End of Life'      | 'CX12S101001'              |'L0805_EOL'| 'NA'                           | 'IO'       | 'EMI FIL CHIP MPZ2012S101AT(100.4A)L-F'         | 'CHIP'         | ''          | ''   | '20120714'  
 'BLM18PG471SN1D'               | 'SMLF'     | 'IND'    | 'CX8PG471000'(!)           = ''              | ''                 | 'CX8PG471000'              |'L0603'| 'BLM18PG471SN1D'               | 'DISCRETE' | 'EMI FILTER BLM18PG471SN1D(470.1000MA)'         | 'CHIP'         | ''          | ''   | '20120714'  
 'BLM18PG471SN1D'               | 'SMLF'     | 'EMPTY'  | 'CX8PG471000'(!)           = ''              | ''                 | 'CX8PG471000'              |'L0603'| 'NA'                           | 'IO'       | 'EMI FILTER BLM18PG471SN1D(470.1000MA)'         | 'CHIP'         | ''          | ''   | '20120714'  
 '220NH'                        | 'SMLF'     | 'IND'    | 'CV+20^0KZ00'(!)           = ''              | ''                 | 'CV+20^0KZ00'              |'L_HCB106480N'| '220NH'                        | 'DISCRETE' | 'IND SMD 220NH +-10% 45A(HCB106480N-221A)'      | 'CHIP'         | ''          | ''   | '20120813'  
 '220NH'                        | 'SMLF'     | 'EMPTY'  | 'CV+20^0KZ00'(!)           = ''              | ''                 | 'CV+20^0KZ00'              |'L_HCB106480N'| 'NA'                           | 'IO'       | 'IND SMD 220NH +-10% 45A(HCB106480N-221A)'      | 'CHIP'         | ''          | ''   | '20120813'  
 '320NH'                        | 'SMLF'     | 'IND'    | 'CV+32^0MZ08'(!)           = ''              | ''                 | 'CV+32^0MZ08'              |'L_HCB1190B'| '320NH'                        | 'DISCRETE' | 'IND SMD 320NH.+-20%.42A(HCB1190-321L)'         | 'CHIP'         | ''          | ''   | '20120829'  
 '320NH'                        | 'SMLF'     | 'EMPTY'  | 'CV+32^0MZ08'(!)           = ''              | ''                 | 'CV+32^0MZ08'              |'L_HCB1190B'| 'NA'                           | 'IO'       | 'IND SMD 320NH.+-20%.42A(HCB1190-321L)'         | 'CHIP'         | ''          | ''   | '20120829'  
 '0.1UH'                        | 'SMLF'     | 'IND'    | 'CV+10G0MZ01'(!)           = ''              | ''                 | 'CV+10G0MZ01'              |'L_MSI-400406'| '0.1UH'                        | 'DISCRETE' | 'IND SMD 0.1UH 20% 16A MSI-400406-R10M-E'       | 'CHIP'         | ''          | ''   | '20120831'  
 '0.1UH'                        | 'SMLF'     | 'EMPTY'  | 'CV+10G0MZ01'(!)           = ''              | ''                 | 'CV+10G0MZ01'              |'L_MSI-400406'| 'NA'                           | 'IO'       | 'IND SMD 0.1UH 20% 16A MSI-400406-R10M-E'       | 'CHIP'         | ''          | ''   | '20120831'  
 '75'                           | 'SMLF'     | 'IND'    | 'CXC8BBPH000'(!)           = ''              | ''                 | 'CXC8BBPH000'              |'L3512'| '75'                           | 'DISCRETE' | 'EMI FILTER C8B BPH 853025+TAPING(75,13A)'      | 'CHIP'         | ''          | ''   | '20120904'  
 '75'                           | 'SMLF'     | 'EMPTY'  | 'CXC8BBPH000'(!)           = ''              | ''                 | 'CXC8BBPH000'              |'L3512'| 'NA'                           | 'IO'       | 'EMI FILTER C8B BPH 853025+TAPING(75,13A)'      | 'CHIP'         | ''          | ''   | '20120904'  
 '1.0UH'                        | 'SMLF'     | 'IND'    | 'CV-1003TZ00'(!)           = ''              | ''                 | 'CV-1003TZ00'              |'L0805'| '1.0UH'                        | 'DISCRETE' | 'EMI FILTER C8B BPH 853025+TAPING(75,13A)'      | 'CHIP'         | ''          | ''   | '20120904'  
 '1.0UH'                        | 'SMLF'     | 'EMPTY'  | 'CV-1003TZ00'(!)           = ''              | ''                 | 'CV-1003TZ00'              |'L0805'| 'NA'                           | 'IO'       | 'EMI FILTER C8B BPH 853025+TAPING(75,13A)'      | 'CHIP'         | ''          | ''   | '20120904'  
 '220/2000MA'                   | 'SMLF'     | 'IND'    | 'CX08S221000'(!)           = ''              | ''                 | 'CX08S221000'              |'L0603'| '220/2000MA'                   | 'DISCRETE' | 'EMI FILTER MHC1608S221NBP(220,2000MA)'         | 'CHIP'         | ''          | ''   | '20120905'  
 '220/2000MA'                   | 'SMLF'     | 'EMPTY'  | 'CX08S221000'(!)           = ''              | ''                 | 'CX08S221000'              |'L0603'| 'NA'                           | 'IO'       | 'EMI FILTER MHC1608S221NBP(220,2000MA)'         | 'CHIP'         | ''          | ''   | '20120905'  
 '2.2UH/46A'                    | 'SMLF'     | 'IND'    | 'CV-22^0MZ01'(!)           = 'End of Design' | 'Comp-Approve'     | 'CV-22^0MZ01'              |'L_MPT1365'| '2.2UH/46A'                    | 'DISCRETE' | 'IND SMD 2.2UH +-20% 46A(MPT1365-2R2H1IN)'      | 'CHIP'         | ''          | ''   | '20120910'  
 '2.2UH/46A'                    | 'SMLF'     | 'EMPTY'  | 'CV-22^0MZ01'(!)           = 'End of Design' | 'Comp-Approve'     | 'CV-22^0MZ01'              |'L_MPT1365'| 'NA'                           | 'IO'       | 'IND SMD 2.2UH +-20% 46A(MPT1365-2R2H1IN)'      | 'CHIP'         | ''          | ''   | '20120910'  
 '220/1500MA'                   | 'SMLF'     | 'IND'    | 'CX221T15000'(!)           = ''              | ''                 | 'CX221T15000'              |'L0603'| '220/1500MA'                   | 'DISCRETE' | 'EMI FILTER HCB1608KF-221T15(220,1500MA)'       | 'CHIP'         | ''          | ''   | '20120917'  
 '220/1500MA'                   | 'SMLF'     | 'EMPTY'  | 'CX221T15000'(!)           = ''              | ''                 | 'CX221T15000'              |'L0603'| 'NA'                           | 'IO'       | 'EMI FILTER HCB1608KF-221T15(220,1500MA)'       | 'CHIP'         | ''          | ''   | '20120917'  
 '220/1.4A'                     | 'SMLF'     | 'IND'    | 'CX8PG221003'(!)           = ''              | ''                 | 'CX8PG221003'              |'L0603'| '220/1.4A'                     | 'DISCRETE' | 'EMI FILTER CHIP BLM18PG221SN1D(220,1.4A)'      | 'CHIP'         | ''          | ''   | '20120917'  
 '220/1.4A'                     | 'SMLF'     | 'EMPTY'  | 'CX8PG221003'(!)           = ''              | ''                 | 'CX8PG221003'              |'L0603'| 'NA'                           | 'IO'       | 'EMI FILTER CHIP BLM18PG221SN1D(220,1.4A)'      | 'CHIP'         | ''          | ''   | '20120917'  
 '270NH/55A'                    | 'SMLF'     | 'IND'    | 'CV+27^0KZ03'(!)           = ''              | ''                 | 'CV+27^0KZ03'              |'L_HCUV117595'| '270NH/55A'                    | 'DISCRETE' | 'IND SMD 270NH +-10% 55A(HCUV117595-271B)'      | 'CHIP'         | ''          | ''   | '20120919'  
 '270NH/55A'                    | 'SMLF'     | 'EMPTY'  | 'CV+27^0KZ03'(!)           = ''              | ''                 | 'CV+27^0KZ03'              |'L_HCUV117595'| 'NA'                           | 'IO'       | 'IND SMD 270NH +-10% 55A(HCUV117595-271B)'      | 'CHIP'         | ''          | ''   | '20120919'  
 '4.7UH/10A'                    | 'SMLF'     | 'IND'    | 'CV-4710MZ14'(!)           = ''              | ''                 | 'CV-4710MZ14'              |'L_MMD-10DE'| '4.7UH/10A'                    | 'DISCRETE' | 'IND SMD 4.7UH +-20%10A(MMD-10DE-4R7M-X2Q'      | 'CHIP'         | ''          | ''   | '20120921'  
 '4.7UH/10A'                    | 'SMLF'     | 'EMPTY'  | 'CV-4710MZ14'(!)           = ''              | ''                 | 'CV-4710MZ14'              |'L_MMD-10DE'| 'NA'                           | 'IO'       | 'IND SMD 4.7UH +-20%10A(MMD-10DE-4R7M-X2Q'      | 'CHIP'         | ''          | ''   | '20120921'  
 '3.3UH/6A'                     | 'SMLF'     | 'IND'    | 'CV-3360MZ07'(!)           = ''              | ''                 | 'CV-3360MZ07'              |'L_PCMC063T'| '3.3UH/6A'                     | 'DISCRETE' | 'IND SMD 3.3UH,6A20%(PCMC063T-3R3MN)'           | 'CHIP'         | ''          | ''   | '20120921'  
 '3.3UH/6A'                     | 'SMLF'     | 'EMPTY'  | 'CV-3360MZ07'(!)           = ''              | ''                 | 'CV-3360MZ07'              |'L_PCMC063T'| 'NA'                           | 'IO'       | 'IND SMD 3.3UH,6A20%(PCMC063T-3R3MN)'           | 'CHIP'         | ''          | ''   | '20120921'  
 '2.2UH/12A'                    | 'SMLF'     | 'IND'    | 'CV-22C0MZ04'(!)           = ''              | ''                 | 'CV-22C0MZ04'              |'L_MMD-10DZ'| '2.2UH/12A'                    | 'DISCRETE' | 'IND SMD 2.2UH+-20%12A(MMD-10DZ-2R2M-X2Q)'      | 'CHIP'         | ''          | ''   | '20121004'  
 '2.2UH/12A'                    | 'SMLF'     | 'EMPTY'  | 'CV-22C0MZ04'(!)           = ''              | ''                 | 'CV-22C0MZ04'              |'L_MMD-10DZ'| 'NA'                           | 'IO'       | 'IND SMD 2.2UH+-20%12A(MMD-10DZ-2R2M-X2Q)'      | 'CHIP'         | ''          | ''   | '20121004'  
 '3.3UH/11A'                    | 'SMLF'     | 'IND'    | 'CV-33B0MZ00'(!)           = ''              | ''                 | 'CV-33B0MZ00'              |'L_MMD-10DE'| '3.3UH/11A'                    | 'DISCRETE' | 'IND SMD 3.3UH 11A +-20%(MMD-10DE-3R3M)'        | 'CHIP'         | ''          | ''   | '20121018'  
 '3.3UH/11A'                    | 'SMLF'     | 'EMPTY'  | 'CV-33B0MZ00'(!)           = ''              | ''                 | 'CV-33B0MZ00'              |'L_MMD-10DE'| 'NA'                           | 'IO'       | 'IND SMD 3.3UH 11A +-20%(MMD-10DE-3R3M)'        | 'CHIP'         | ''          | ''   | '20121018'  
 '3.3UH/5A'                     | 'SMLF'     | 'IND'    | 'CV-3350MZ04'(!)           = ''              | ''                 | 'CV-3350MZ04'              |'L_MMD-05CZ-3R3M-M2Q'| '3.3UH/5A'                     | 'DISCRETE' | 'IND SMD 3.3U +-20% 5A(MMD-05CZ-3R3M-M2Q)'      | 'CHIP'         | ''          | ''   | '20121018'  
 '3.3UH/5A'                     | 'SMLF'     | 'EMPTY'  | 'CV-3350MZ04'(!)           = ''              | ''                 | 'CV-3350MZ04'              |'L_MMD-05CZ-3R3M-M2Q'| 'NA'                           | 'IO'       | 'IND SMD 3.3U +-20% 5A(MMD-05CZ-3R3M-M2Q)'      | 'CHIP'         | ''          | ''   | '20121018'  
 '2.2UH/5.5A'                   | 'SMLF'     | 'IND'    | 'CV-2255MZ01'(!)           = ''              | ''                 | 'CV-2255MZ01'              |'L_MMD-05CZ-2R2M-X2Q'| '2.2UH/5.5A'                   | 'DISCRETE' | 'IND SMD 2.2UH 20% 5.5A MMD-05CZ-2R2M-X2Q'      | 'CHIP'         | ''          | ''   | '20121018'  
 '2.2UH/5.5A'                   | 'SMLF'     | 'EMPTY'  | 'CV-2255MZ01'(!)           = ''              | ''                 | 'CV-2255MZ01'              |'L_MMD-05CZ-2R2M-X2Q'| 'NA'                           | 'IO'       | 'IND SMD 2.2UH 20% 5.5A MMD-05CZ-2R2M-X2Q'      | 'CHIP'         | ''          | ''   | '20121018'  
 'BLM21AH601SN1D'               | 'SMLF'     | 'IND'    | 'CX21AH60002'(!)           = 'End of Design' | 'End of Life'      | 'CX21AH60002'              |'L0805_EOL'| 'BLM21AH601SN1D'               | 'DISCRETE' | 'EMI FILTER BLM21AH601SN1D(600@100MHZ)'         | 'CHIP'         | ''          | ''   | '20121024'  
 'BLM21AH601SN1D'               | 'SMLF'     | 'EMPTY'  | 'CX21AH60002'(!)           = 'End of Design' | 'End of Life'      | 'CX21AH60002'              |'L0805_EOL'| 'NA'                           | 'IO'       | 'EMI FILTER BLM21AH601SN1D(600@100MHZ)'         | 'CHIP'         | ''          | ''   | '20121024'  
 '1.5UH/4A'                     | 'SMLF'     | 'IND'    | 'CV-1540MZ02'(!)           = ''              | ''                 | 'CV-1540MZ02'              |'L_MMD-04BZ-1R5M-X2'| '1.5UH/4A'                     | 'DISCRETE' | 'IND SMD 1.5UH 20% 4A MMD-04BZ-1R5M-X2'         | 'CHIP'         | ''          | ''   | '20121030'  
 '1.5UH/4A'                     | 'SMLF'     | 'EMPTY'  | 'CV-1540MZ02'(!)           = ''              | ''                 | 'CV-1540MZ02'              |'L_MMD-04BZ-1R5M-X2'| 'NA'                           | 'IO'       | 'IND SMD 1.5UH 20% 4A MMD-04BZ-1R5M-X2'         | 'CHIP'         | ''          | ''   | '20121030'  
 '220NH/60A'                    | 'SMLF'     | 'IND'    | 'TMP_T2H_KC_1130_1'(!)     = ''              | ''                 | 'TMP_T2H_KC_1130_1'        |'L_HCB147270-221'| '220NH/60A'                    | 'DISCRETE' | 'IND SMD 220NH.+-20%.60A(HCB147270-221)'        | 'CHIP'         | ''          | ''   | '20121030'  
 '220NH/60A'                    | 'SMLF'     | 'EMPTY'  | 'TMP_T2H_KC_1130_1'(!)     = ''              | ''                 | 'TMP_T2H_KC_1130_1'        |'L_HCB147270-221'| 'NA'                           | 'IO'       | 'IND SMD 220NH.+-20%.60A(HCB147270-221)'        | 'CHIP'         | ''          | ''   | '20121030'  
 '220NH/57A'                    | 'SMLF'     | 'IND'    | 'TMP_T2H_KC_1130_2'(!)     = ''              | ''                 | 'TMP_T2H_KC_1130_2'        |'L_HCB147070-221'| '220NH/57A'                    | 'DISCRETE' | 'IND SMD 220NH.+-20%.57A(HCB147070-221)'        | 'CHIP'         | ''          | ''   | '20121030'  
 '220NH/57A'                    | 'SMLF'     | 'EMPTY'  | 'TMP_T2H_KC_1130_2'(!)     = ''              | ''                 | 'TMP_T2H_KC_1130_2'        |'L_HCB147070-221'| 'NA'                           | 'IO'       | 'IND SMD 220NH.+-20%.57A(HCB147070-221)'        | 'CHIP'         | ''          | ''   | '20121030'  
 'BLM21PG300SN1D'               | 'SMLF'     | 'IND'    | 'CX1PG300008'(!)           = ''              | ''                 | 'CX1PG300008'              |'L0805'| 'BLM21PG300SN1D'               | 'DISCRETE' | 'EMI FILTER CHIP BLM21PG300SN1D(30. 3A)'        | 'CHIP'         | ''          | ''   | '20121204'  
 'BLM21PG300SN1D'               | 'SMLF'     | 'EMPTY'  | 'CX1PG300008'(!)           = ''              | ''                 | 'CX1PG300008'              |'L0805'| 'NA'                           | 'IO'       | 'EMI FILTER CHIP BLM21PG300SN1D(30. 3A)'        | 'CHIP'         | ''          | ''   | '20121204'  
 '0.24UH/28A'                   | 'SMLF'     | 'IND'    | 'CV+24T0MZ00'(!)           = ''              | ''                 | 'CV+24T0MZ00'              |'L_MMD-06CZ'| '0.24UH/28A'                   | 'DISCRETE' | 'IND SMD0.24UH+-20%28A(MMD-06CZNR24MEM1Q)'      | 'CHIP'         | ''          | ''   | '20121212'  
 '0.24UH/28A'                   | 'SMLF'     | 'EMPTY'  | 'CV+24T0MZ00'(!)           = ''              | ''                 | 'CV+24T0MZ00'              |'L_MMD-06CZ'| 'NA'                           | 'IO'       | 'IND SMD0.24UH+-20%28A(MMD-06CZNR24MEM1Q)'      | 'CHIP'         | ''          | ''   | '20121212'  
 '0.22UH/30A'                   | 'SMLF'     | 'IND'    | 'CV+22V0MZ01'(!)           = ''              | ''                 | 'CV+22V0MZ01'              |'L_MMD-06DZ'| '0.22UH/30A'                   | 'DISCRETE' | 'IND SMD 0.22UH 20%30A(MMD-06DZ-R22M-X2Q)'      | 'CHIP'         | ''          | ''   | '20121212'  
 '0.22UH/30A'                   | 'SMLF'     | 'EMPTY'  | 'CV+22V0MZ01'(!)           = ''              | ''                 | 'CV+22V0MZ01'              |'L_MMD-06DZ'| 'NA'                           | 'IO'       | 'IND SMD 0.22UH 20%30A(MMD-06DZ-R22M-X2Q)'      | 'CHIP'         | ''          | ''   | '20121212'  
 '4.7UH/3.5A'                   | 'SMLF'     | 'IND'    | 'CV-4735MZ00'(!)           = ''              | ''                 | 'CV-4735MZ00'              |'L_MMD-05AH'| '4.7UH/3.5A'                   | 'DISCRETE' | 'IND SMD 4.7U,3.5A,20%(MMD-05AH-4R7M-X2Q)'      | 'CHIP'         | ''          | ''   | '20121212'  
 '4.7UH/3.5A'                   | 'SMLF'     | 'EMPTY'  | 'CV-4735MZ00'(!)           = ''              | ''                 | 'CV-4735MZ00'              |'L_MMD-05AH'| 'NA'                           | 'IO'       | 'IND SMD 4.7U,3.5A,20%(MMD-05AH-4R7M-X2Q)'      | 'CHIP'         | ''          | ''   | '20121212'  
 '10UH/2.5A'                    | 'SMLF'     | 'IND'    | 'CV01025MZ02'(!)           = ''              | ''                 | 'CV01025MZ02'              |'L_MMD-05AH'| '10UH/2.5A'                    | 'DISCRETE' | 'IND SMD 10UH+-20% 2.5A MMD-05AH-100M-X2Q'      | 'CHIP'         | ''          | ''   | '20121212'  
 '10UH/2.5A'                    | 'SMLF'     | 'EMPTY'  | 'CV01025MZ02'(!)           = ''              | ''                 | 'CV01025MZ02'              |'L_MMD-05AH'| 'NA'                           | 'IO'       | 'IND SMD 10UH+-20% 2.5A MMD-05AH-100M-X2Q'      | 'CHIP'         | ''          | ''   | '20121212'  
 'MPZ1608S300AT/5A'             | 'SMLF'     | 'IND'    | 'CX08S300000'(!)           = 'End of Design' | 'Comp-Approve'     | 'CX08S300000'              |'L0603'| 'MPZ1608S300AT/5A'             | 'DISCRETE' | 'EMI FILTER CHIP MPZ1608S300AT(30,5A)'          | 'CHIP'         | ''          | ''   | '20121214'  
 'MPZ1608S300AT/5A'             | 'SMLF'     | 'EMPTY'  | 'CX08S300000'(!)           = 'End of Design' | 'Comp-Approve'     | 'CX08S300000'              |'L0603'| 'NA'                           | 'IO'       | 'EMI FILTER CHIP MPZ1608S300AT(30,5A)'          | 'CHIP'         | ''          | ''   | '20121214'  
 'MPZ2012S221AT/3A'             | 'SMLF'     | 'IND'    | 'CX12S221001'(!)           = 'End of Design' | 'End of Life'      | 'CX12S221001'              |'L0805_EOL'| 'MPZ2012S221AT/3A'             | 'DISCRETE' | 'EMI FILTER CHIP MPZ2012S221AT(220,3A)'         | 'CHIP'         | ''          | ''   | '20121214'  
 'MPZ2012S221AT/3A'             | 'SMLF'     | 'EMPTY'  | 'CX12S221001'(!)           = 'End of Design' | 'End of Life'      | 'CX12S221001'              |'L0805_EOL'| 'NA'                           | 'IO'       | 'EMI FILTER CHIP MPZ2012S221AT(220,3A)'         | 'CHIP'         | ''          | ''   | '20121214'  
 'BLM15AX601SN1D/420MA'         | 'SMLF'     | 'IND'    | 'CX5AX601000'(!)           = ''              | ''                 | 'CX5AX601000'              |'L0402'| 'BLM15AX601SN1D/420MA'         | 'DISCRETE' | 'EMI FILTER BLM15AX601SN1D(600,420MA)'          | 'CHIP'         | ''          | ''   | '20121222'  
 'BLM15AX601SN1D/420MA'         | 'SMLF'     | 'EMPTY'  | 'CX5AX601000'(!)           = ''              | ''                 | 'CX5AX601000'              |'L0402'| 'NA'                           | 'IO'       | 'EMI FILTER BLM15AX601SN1D(600,420MA)'          | 'CHIP'         | ''          | ''   | '20121222'  
 '0.36UH/45A'                   | 'SMLF'     | 'IND'    | 'CV+36^0KZ00'(!)           = ''              | ''                 | 'CV+36^0KZ00'              |'L_HCUV117595'| '0.36UH/45A'                   | 'DISCRETE' | 'IND SMD 0.36UH +-10% 45A(HCUV117595-361B'      | 'CHIP'         | ''          | ''   | '20121227'  
 '0.36UH/45A'                   | 'SMLF'     | 'EMPTY'  | 'CV+36^0KZ00'(!)           = ''              | ''                 | 'CV+36^0KZ00'              |'L_HCUV117595'| 'NA'                           | 'IO'       | 'IND SMD 0.36UH +-10% 45A(HCUV117595-361B'      | 'CHIP'         | ''          | ''   | '20121227'  
 '0.47UH/45A'                   | 'SMLF'     | 'IND'    | 'CV+47^0KZ02'(!)           = ''              | ''                 | 'CV+47^0KZ02'              |'L_HCUV117595'| '0.47UH/45A'                   | 'DISCRETE' | 'IND SMD 0.47UH +-10% 45A(HCUV117595-471B'      | 'CHIP'         | ''          | ''   | '20121227'  
 '0.47UH/45A'                   | 'SMLF'     | 'EMPTY'  | 'CV+47^0KZ02'(!)           = ''              | ''                 | 'CV+47^0KZ02'              |'L_HCUV117595'| 'NA'                           | 'IO'       | 'IND SMD 0.47UH +-10% 45A(HCUV117595-471B'      | 'CHIP'         | ''          | ''   | '20121227'  
 '2.2UH/5.5A'                   | 'SMLF'     | 'IND'    | 'CV-2255MZ00'(!)           = ''              | ''                 | 'CV-2255MZ00'              |'L_MMD-05CZ-2R2M-X1Q'| '2.2UH/5.5A'                   | 'DISCRETE' | 'IND SMD 2.2UH 20% 5.5A MMD-05CZ-2R2M-X1Q'      | 'CHIP'         | ''          | ''   | '20130103'  
 '2.2UH/5.5A'                   | 'SMLF'     | 'EMPTY'  | 'CV-2255MZ00'(!)           = ''              | ''                 | 'CV-2255MZ00'              |'L_MMD-05CZ-2R2M-X1Q'| 'NA'                           | 'IO'       | 'IND SMD 2.2UH 20% 5.5A MMD-05CZ-2R2M-X1Q'      | 'CHIP'         | ''          | ''   | '20130103'  
 'HCB1608KF-601T10/1A'          | 'SMLF'     | 'IND'    | 'CX601T10000'(!)           = ''              | ''                 | 'CX601T10000'              |'L0603'| 'HCB1608KF-601T10/1A'          | 'DISCRETE' | 'EMI FILTER CHIP HCB1608KF-601T10(600,1A)'      | 'CHIP'         | ''          | ''   | '20130103'  
 'HCB1608KF-601T10/1A'          | 'SMLF'     | 'EMPTY'  | 'CX601T10000'(!)           = ''              | ''                 | 'CX601T10000'              |'L0603'| 'NA'                           | 'IO'       | 'EMI FILTER CHIP HCB1608KF-601T10(600,1A)'      | 'CHIP'         | ''          | ''   | '20130103'  
 '220NH/45A'                    | 'SMLF'     | 'IND'    | 'CV+22^0EZ00'(!)           = ''              | ''                 | 'CV+22^0EZ00'              |'L_HCUV117595'| '220NH/45A'                    | 'DISCRETE' | 'IND SMD 220NH +-15% 45A(HCUV117595-221)'       | 'CHIP'         | ''          | ''   | '20130114'  
 '220NH/45A'                    | 'SMLF'     | 'EMPTY'  | 'CV+22^0EZ00'(!)           = ''              | ''                 | 'CV+22^0EZ00'              |'L_HCUV117595'| 'NA'                           | 'IO'       | 'IND SMD 220NH +-15% 45A(HCUV117595-221)'       | 'CHIP'         | ''          | ''   | '20130114'  
 '10UH/2.5A'                    | 'SMLF'     | 'IND'    | 'CV01025MZ03'(!)           = ''              | ''                 | 'CV01025MZ03'              |'L_MMD-05CZ-3R3M-M2Q'| '10UH/2.5A'                    | 'DISCRETE' | 'IND SMD 10UH 20% 2.5A MMD-05CZ-100M-V1Q'       | 'CHIP'         | ''          | ''   | '20130115'  
 '10UH/2.5A'                    | 'SMLF'     | 'EMPTY'  | 'CV01025MZ03'(!)           = ''              | ''                 | 'CV01025MZ03'              |'L_MMD-05CZ-3R3M-M2Q'| 'NA'                           | 'IO'       | 'IND SMD 10UH 20% 2.5A MMD-05CZ-100M-V1Q'       | 'CHIP'         | ''          | ''   | '20130115'  
 '1.0UH/9.2A'                   | 'SMLF'     | 'IND'    | 'CV-1092MZ00'(!)           = ''              | ''                 | 'CV-1092MZ00'              |'L_MMD-05CZ-3R3M-M2Q'| '1.0UH/9.2A'                   | 'DISCRETE' | 'IND SMD 1.0UH 20% 9.2A MMD-05CZ-1R0M-V1Q'      | 'CHIP'         | ''          | ''   | '20130115'  
 '1.0UH/9.2A'                   | 'SMLF'     | 'EMPTY'  | 'CV-1092MZ00'(!)           = ''              | ''                 | 'CV-1092MZ00'              |'L_MMD-05CZ-3R3M-M2Q'| 'NA'                           | 'IO'       | 'IND SMD 1.0UH 20% 9.2A MMD-05CZ-1R0M-V1Q'      | 'CHIP'         | ''          | ''   | '20130115'  
 '0.47UH/12.2A'                 | 'SMLF'     | 'IND'    | 'CV+47C2MZ00'(!)           = ''              | ''                 | 'CV+47C2MZ00'              |'L_MMD-05CZ-3R3M-M2Q'| '0.47UH/12.2A'                 | 'DISCRETE' | 'IND SMD 0.47UH 20% 12.2A MMD-05CZ-R47M-V'      | 'CHIP'         | ''          | ''   | '20130115'  
 '0.47UH/12.2A'                 | 'SMLF'     | 'EMPTY'  | 'CV+47C2MZ00'(!)           = ''              | ''                 | 'CV+47C2MZ00'              |'L_MMD-05CZ-3R3M-M2Q'| 'NA'                           | 'IO'       | 'IND SMD 0.47UH 20% 12.2A MMD-05CZ-R47M-V'      | 'CHIP'         | ''          | ''   | '20130115'  
 '1UH/20A'                      | 'SMLF'     | 'IND'    | 'CV-10K0MZ03'(!)           = ''              | ''                 | 'CV-10K0MZ03'              |'L_PB103E'| '1UH/20A'                      | 'DISCRETE' | 'IND SMD 1UH(20%,20A)PCMB103E-1R0MS'            | 'CHIP'         | ''          | ''   | '20130123'  
 '1UH/20A'                      | 'SMLF'     | 'EMPTY'  | 'CV-10K0MZ03'(!)           = ''              | ''                 | 'CV-10K0MZ03'              |'L_PB103E'| 'NA'                           | 'IO'       | 'IND SMD 1UH(20%,20A)PCMB103E-1R0MS'            | 'CHIP'         | ''          | ''   | '20130123'  
 '0.36UH/55A'                   | 'SMLF'     | 'IND'    | 'CV+36^0KZ01'(!)           = ''              | ''                 | 'CV+36^0KZ01'              |'L_THMPF2509'| '0.36UH/55A'                   | 'DISCRETE' | 'IND SMD 0.36UH +-10% 55A(HCUV138795-361B'      | 'CHIP'         | ''          | ''   | '20130220'  
 '0.36UH/55A'                   | 'SMLF'     | 'EMPTY'  | 'CV+36^0KZ01'(!)           = ''              | ''                 | 'CV+36^0KZ01'              |'L_THMPF2509'| 'NA'                           | 'IO'       | 'IND SMD 0.36UH +-10% 55A(HCUV138795-361B'      | 'CHIP'         | ''          | ''   | '20130220'  
 '1UH/13A'                      | 'SMLF'     | 'IND'    | 'CV-10D0MZ08'(!)           = ''              | ''                 | 'CV-10D0MZ08'              |'L_PCMB065T'| '1UH/13A'                      | 'DISCRETE' | 'IND SMD 1UH +-20% 13A(PCMB065T-1R0MS)'         | 'CHIP'         | ''          | ''   | '20130226'  
 '1UH/13A'                      | 'SMLF'     | 'EMPTY'  | 'CV-10D0MZ08'(!)           = ''              | ''                 | 'CV-10D0MZ08'              |'L_PCMB065T'| 'NA'                           | 'IO'       | 'IND SMD 1UH +-20% 13A(PCMB065T-1R0MS)'         | 'CHIP'         | ''          | ''   | '20130226'  
 '270NH/62.5A'                  | 'SMLF'     | 'IND'    | 'TMP_TUIJ_KC_0307_1'(!)    = ''              | ''                 | 'TMP_TUIJ_KC_0307_1'       |'L_HCB149070'| '270NH/62.5A'                  | 'DISCRETE' | 'IND SMD 270NH.+-15%.62.5A(HCB149070-271)'      | 'CHIP'         | ''          | ''   | '20130307'  
 '270NH/62.5A'                  | 'SMLF'     | 'EMPTY'  | 'TMP_TUIJ_KC_0307_1'(!)    = ''              | ''                 | 'TMP_TUIJ_KC_0307_1'       |'L_HCB149070'| 'NA'                           | 'IO'       | 'IND SMD 270NH.+-15%.62.5A(HCB149070-271)'      | 'CHIP'         | ''          | ''   | '20130307'  
 '270NH/55A'                    | 'SMLF'     | 'IND'    | 'TMP_TUIJ_KC_0314_1'(!)    = ''              | ''                 | 'TMP_TUIJ_KC_0314_1'       |'L_HCUV147570'| '270NH/55A'                    | 'DISCRETE' | 'IND SMD 270NH.+-10%.55A(HCUV147570-271)'       | 'CHIP'         | ''          | ''   | '20130314'  
 '270NH/55A'                    | 'SMLF'     | 'EMPTY'  | 'TMP_TUIJ_KC_0314_1'(!)    = ''              | ''                 | 'TMP_TUIJ_KC_0314_1'       |'L_HCUV147570'| 'NA'                           | 'IO'       | 'IND SMD 270NH.+-10%.55A(HCUV147570-271)'       | 'CHIP'         | ''          | ''   | '20130314'  
 '0.32UH/43A'                   | 'SMLF'     | 'IND'    | 'CV+32^0MZ09'(!)           = ''              | ''                 | 'CV+32^0MZ09'              |'L_HCB141390'| '0.32UF/43A'                   | 'DISCRETE' | 'IND SMD 0.32U 20% 43A(HCB141390-321-F)'        | 'CHIP'         | ''          | ''   | '20130319'  
 '0.32UH/43A'                   | 'SMLF'     | 'EMPTY'  | 'CV+32^0MZ09'(!)           = ''              | ''                 | 'CV+32^0MZ09'              |'L_HCB141390'| 'NA'                           | 'IO'       | 'IND SMD 0.32U 20% 43A(HCB141390-321-F)'        | 'CHIP'         | ''          | ''   | '20130319'  
 '0.1UH/40A'                    | 'SMLF'     | 'IND'    | 'CV+10^0MZ08'(!)           = 'Non-Preferred' | 'End of Life'      | 'CV+10^0MZ08'              |'L_L30909-7_EOL'| '0.1UH/40A'                    | 'DISCRETE' | 'IND SMD 0.1UH +-20% 40A(L30909-7)'             | 'CHIP'         | ''          | ''   | '20130327'  
 '0.1UH/40A'                    | 'SMLF'     | 'EMPTY'  | 'CV+10^0MZ08'(!)           = 'Non-Preferred' | 'End of Life'      | 'CV+10^0MZ08'              |'L_L30909-7_EOL'| 'NA'                           | 'IO'       | 'IND SMD 0.1UH +-20% 40A(L30909-7)'             | 'CHIP'         | ''          | ''   | '20130327'  
 '270NH/55A'                    | 'SMLF'     | 'IND'    | 'CV+27^0KZ05'(!)           = ''              | ''                 | 'CV+27^0KZ05'              |'L_HCUV147570'| '270NH/55A'                    | 'DISCRETE' | 'IND SMD 270NH +-10% 55A(HCUV147570-271)'       | 'CHIP'         | ''          | ''   | '20130403'  
 '270NH/55A'                    | 'SMLF'     | 'EMPTY'  | 'CV+27^0KZ05'(!)           = ''              | ''                 | 'CV+27^0KZ05'              |'L_HCUV147570'| 'NA'                           | 'IO'       | 'IND SMD 270NH +-10% 55A(HCUV147570-271)'       | 'CHIP'         | ''          | ''   | '20130403'  
 '270NH/0.55A'                  | 'SMLF'     | 'IND'    | 'CV+27^0KZ06'(!)           = ''              | ''                 | 'CV+27^0KZ06'              |'L_HCUV148070'| '270NH/0.55A'                  | 'DISCRETE' | 'IND SMD 270NH.+-10%.55A(HCUV148070-271)'       | 'CHIP'         | ''          | ''   | '20130410'  
 '270NH/0.55A'                  | 'SMLF'     | 'EMPTY'  | 'CV+27^0KZ06'(!)           = ''              | ''                 | 'CV+27^0KZ06'              |'L_HCUV148070'| 'NA'                           | 'IO'       | 'IND SMD 270NH.+-10%.55A(HCUV148070-271)'       | 'CHIP'         | ''          | ''   | '20130410'  
 'BLM15PX600SN1D/2.5A'          | 'SMLF'     | 'IND'    | 'CX5PX600000'(!)           = ''              | ''                 | 'CX5PX600000'              |'L0402'| 'BLM15PX600SN1D/2.5A'          | 'DISCRETE' | 'EMI FILTER CHIP BLM15PX600SN1D(60, 2.5A)'      | 'CHIP'         | ''          | ''   | '20130422'  
 'BLM15PX600SN1D/2.5A'          | 'SMLF'     | 'EMPTY'  | 'CX5PX600000'(!)           = ''              | ''                 | 'CX5PX600000'              |'L0402'| 'NA'                           | 'IO'       | 'EMI FILTER CHIP BLM15PX600SN1D(60, 2.5A)'      | 'CHIP'         | ''          | ''   | '20130422'  
 '0.1UH/30A'                    | 'SMLF'     | 'IND'    | 'CV+10V0MZ00'(!)           = 'Non-Preferred' | 'End of Life'      | 'CV+10V0MZ00'              |'L_L30909-6_EOL'| '0.1UH/30A'                    | 'DISCRETE' | 'IND SMD 0.1UH +-20% 30A(L30909-6)'             | 'CHIP'         | ''          | ''   | '20130425'  
 '0.1UH/30A'                    | 'SMLF'     | 'EMPTY'  | 'CV+10V0MZ00'(!)           = 'Non-Preferred' | 'End of Life'      | 'CV+10V0MZ00'              |'L_L30909-6_EOL'| 'NA'                           | 'IO'       | 'IND SMD 0.1UH +-20% 30A(L30909-6)'             | 'CHIP'         | ''          | ''   | '20130425'  
 'BLM18SG331TN1D/1.5A'          | 'SMLF'     | 'IND'    | 'CX8SG331000'(!)           = 'End of Design' | 'Comp-Approve'     | 'CX8SG331000'              |'L0603'| 'BLM18SG331TN1D/1.5A'          | 'DISCRETE' | 'EMI FILTER BLM18SG331TN1D(330,1.5A)'           | 'CHIP'         | ''          | ''   | '20130520'  
 'BLM18SG331TN1D/1.5A'          | 'SMLF'     | 'EMPTY'  | 'CX8SG331000'(!)           = 'End of Design' | 'Comp-Approve'     | 'CX8SG331000'              |'L0603'| 'NA'                           | 'IO'       | 'EMI FILTER BLM18SG331TN1D(330,1.5A)'           | 'CHIP'         | ''          | ''   | '20130520'  
 '0.22UH/87A'                   | 'SMLF'     | 'IND'    | 'CV+22^0KZ06'(!)           = ''              | ''                 | 'CV+22^0KZ06'              |'L_HCB138795-221B'| '0.22UH/87A'                   | 'DISCRETE' | 'IND SMD 0.22UH +-10% 87A(HCUV138795-221B'      | 'CHIP'         | ''          | ''   | '20130523'  
 '0.22UH/87A'                   | 'SMLF'     | 'EMPTY'  | 'CV+22^0KZ06'(!)           = ''              | ''                 | 'CV+22^0KZ06'              |'L_HCB138795-221B'| 'NA'                           | 'IO'       | 'IND SMD 0.22UH +-10% 87A(HCUV138795-221B'      | 'CHIP'         | ''          | ''   | '20130523'  
 '0.27UH/70A'                   | 'SMLF'     | 'IND'    | 'CV+27^0KZ08'(!)           = ''              | ''                 | 'CV+27^0KZ08'              |'L_HCUV138795L-271'| '0.27UH/70A'                   | 'DISCRETE' | 'IND SMD 0.27UH +-10% 70A(HCUV138795L-271'      | 'CHIP'         | ''          | ''   | '20130523'  
 '0.27UH/70A'                   | 'SMLF'     | 'EMPTY'  | 'CV+27^0KZ08'(!)           = ''              | ''                 | 'CV+27^0KZ08'              |'L_HCUV138795L-271'| 'NA'                           | 'IO'       | 'IND SMD 0.27UH +-10% 70A(HCUV138795L-271'      | 'CHIP'         | ''          | ''   | '20130523'  
 '1000UH/0.1A'                  | 'SMLF'     | 'IND'    | 'CV21001MZ01'(!)           = ''              | ''                 | 'CV21001MZ01'              |'L_MLPS-4018'| '1000UH/0.1A'                  | 'DISCRETE' | 'IND SMD 1000UH 20% 0.1A(MLPS-4018-102M)'       | 'CHIP'         | ''          | ''   | '20130610'  
 '1000UH/0.1A'                  | 'SMLF'     | 'EMPTY'  | 'CV21001MZ01'(!)           = ''              | ''                 | 'CV21001MZ01'              |'L_MLPS-4018'| 'NA'                           | 'IO'       | 'IND SMD 1000UH 20% 0.1A(MLPS-4018-102M)'       | 'CHIP'         | ''          | ''   | '20130610'  
 '2.2UH/40A'                    | 'SMLF'     | 'IND'    | 'CV-22^0MZ02'(!)           = ''              | ''                 | 'CV-22^0MZ02'              |'L_MMD12FD'| '2.2UH/40A'                    | 'DISCRETE' | 'IND SMD 2.2UH 20% 40A(MMD-12FD-2R2M-V1Q)'      | 'CHIP'         | ''          | ''   | '20130614'  
 '2.2UH/40A'                    | 'SMLF'     | 'EMPTY'  | 'CV-22^0MZ02'(!)           = ''              | ''                 | 'CV-22^0MZ02'              |'L_MMD12FD'| 'NA'                           | 'IO'       | 'IND SMD 2.2UH 20% 40A(MMD-12FD-2R2M-V1Q)'      | 'CHIP'         | ''          | ''   | '20130614'  
 '3.3UH/10A'                    | 'SMLF'     | 'IND'    | 'CV-33A0MZ02'(!)           = ''              | ''                 | 'CV-33A0MZ02'              |'L_PCMB104TXB'| '3.3UH/10A'                    | 'DISCRETE' | 'IND SMD 3.3UH+-20%10A(PCMB104T-3R3MS)'         | 'CHIP'         | ''          | ''   | '20130619'  
 '3.3UH/10A'                    | 'SMLF'     | 'EMPTY'  | 'CV-33A0MZ02'(!)           = ''              | ''                 | 'CV-33A0MZ02'              |'L_PCMB104TXB'| 'NA'                           | 'IO'       | 'IND SMD 3.3UH+-20%10A(PCMB104T-3R3MS)'         | 'CHIP'         | ''          | ''   | '20130619'  
 'BLM18BB470/500MA'             | 'SMLF'     | 'IND'    | 'CX8BB470007'(!)           = ''              | ''                 | 'CX8BB470007'              |'L0603'| 'BLM18BB470/500MA'             | 'DISCRETE' | 'EMI FILTER CHIP BLM18BB470(47.500MA)'          | 'CHIP'         | ''          | ''   | '20130704'  
 'BLM18BB470/500MA'             | 'SMLF'     | 'EMPTY'  | 'CX8BB470007'(!)           = ''              | ''                 | 'CX8BB470007'              |'L0603'| 'NA'                           | 'IO'       | 'EMI FILTER CHIP BLM18BB470(47.500MA)'          | 'CHIP'         | ''          | ''   | '20130704'  
 '1.0UH/2.22A'                  | 'SMLF'     | 'IND'    | 'CV-1023TZ02'(!)           = ''              | ''                 | 'CV-1023TZ02'              |'L_VLF302510MT-1R0N'| '1.0UH/2.22A'                  | 'DISCRETE' | 'IND SMD 1.0U 30% 2.22A(VLF302510MT-1R0N)'      | 'CHIP'         | ''          | ''   | '20130715'  
 '1.0UH/2.22A'                  | 'SMLF'     | 'EMPTY'  | 'CV-1023TZ02'(!)           = ''              | ''                 | 'CV-1023TZ02'              |'L_VLF302510MT-1R0N'| 'NA'                           | 'IO'       | 'IND SMD 1.0U 30% 2.22A(VLF302510MT-1R0N)'      | 'CHIP'         | ''          | ''   | '20130715'  
 '1.0UH/50A'                    | 'SMLF'     | 'IND'    | 'CV-10^0KZ00'(!)           = ''              | ''                 | 'CV-10^0KZ00'              |'L_HCBD141312'| '1.0UH/50A'                    | 'DISCRETE' | 'IND SMD 1.0UH +-10% 50A(HCBD141312-102)'       | 'CHIP'         | ''          | ''   | '20130726'  
 '1.0UH/50A'                    | 'SMLF'     | 'EMPTY'  | 'CV-10^0KZ00'(!)           = ''              | ''                 | 'CV-10^0KZ00'              |'L_HCBD141312'| 'NA'                           | 'IO'       | 'IND SMD 1.0UH +-10% 50A(HCBD141312-102)'       | 'CHIP'         | ''          | ''   | '20130726'  
 '1.2UH/43A'                    | 'SMLF'     | 'IND'    | 'CV-12^0KZ00'(!)           = ''              | ''                 | 'CV-12^0KZ00'              |'L_HCBD141312'| '1.2UH/43A'                    | 'DISCRETE' | 'IND SMD 1.2UH +-10% 43A(HCBD141312-122)'       | 'CHIP'         | ''          | ''   | '20130726'  
 '1.2UH/43A'                    | 'SMLF'     | 'EMPTY'  | 'CV-12^0KZ00'(!)           = ''              | ''                 | 'CV-12^0KZ00'              |'L_HCBD141312'| 'NA'                           | 'IO'       | 'IND SMD 1.2UH +-10% 43A(HCBD141312-122)'       | 'CHIP'         | ''          | ''   | '20130726'  
 '1.5UH/34A'                    | 'SMLF'     | 'IND'    | 'CV-15Z0KZ00'(!)           = ''              | ''                 | 'CV-15Z0KZ00'              |'L_HCBD141312'| '1.5UH/34A'                    | 'DISCRETE' | 'IND SMD 1.5UH +-10% 34A(HCBD141312-152)'       | 'CHIP'         | ''          | ''   | '20130726'  
 '1.5UH/34A'                    | 'SMLF'     | 'EMPTY'  | 'CV-15Z0KZ00'(!)           = ''              | ''                 | 'CV-15Z0KZ00'              |'L_HCBD141312'| 'NA'                           | 'IO'       | 'IND SMD 1.5UH +-10% 34A(HCBD141312-152)'       | 'CHIP'         | ''          | ''   | '20130726'  
 '2.2UH/24A'                    | 'SMLF'     | 'IND'    | 'CV-22P0KZ00'(!)           = ''              | ''                 | 'CV-22P0KZ00'              |'L_HCBD141312'| '2.2UH/24A'                    | 'DISCRETE' | 'IND SMD 2.2UH +-10% 24A(HCBD141312-222)'       | 'CHIP'         | ''          | ''   | '20130726'  
 '2.2UH/24A'                    | 'SMLF'     | 'EMPTY'  | 'CV-22P0KZ00'(!)           = ''              | ''                 | 'CV-22P0KZ00'              |'L_HCBD141312'| 'NA'                           | 'IO'       | 'IND SMD 2.2UH +-10% 24A(HCBD141312-222)'       | 'CHIP'         | ''          | ''   | '20130726'  
 'MPZ2012S601AT/2A'             | 'SMLF'     | 'IND'    | 'CX12S601000'(!)           = 'End of Design' | 'End of Life'      | 'CX12S601000'              |'L0805_EOL'| 'MPZ2012S601AT/2A'             | 'DISCRETE' | 'EMI FIL CHIP MPZ2012S601AT(600,2A)'            | 'CHIP'         | ''          | ''   | '20130731'  
 'MPZ2012S601AT/2A'             | 'SMLF'     | 'EMPTY'  | 'CX12S601000'(!)           = 'End of Design' | 'End of Life'      | 'CX12S601000'              |'L0805_EOL'| 'NA'                           | 'IO'       | 'EMI FIL CHIP MPZ2012S601AT(600,2A)'            | 'CHIP'         | ''          | ''   | '20130731'  
 '1.5UH/27A'                    | 'SMLF'     | 'IND'    | 'CV-15S0MZ00'(!)           = ''              | ''                 | 'CV-15S0MZ00'              |'L_MMD12FD'| '1.5UH/27A'                    | 'DISCRETE' | 'IND SMD 1.5UH 20% 27A MMD-12FD-1R5M-V1Q'       | 'CHIP'         | ''          | ''   | '20130805'  
 '1.5UH/27A'                    | 'SMLF'     | 'EMPTY'  | 'CV-15S0MZ00'(!)           = ''              | ''                 | 'CV-15S0MZ00'              |'L_MMD12FD'| 'NA'                           | 'IO'       | 'IND SMD 1.5UH 20% 27A MMD-12FD-1R5M-V1Q'       | 'CHIP'         | ''          | ''   | '20130805'  
 '3.3UH/18A'                    | 'SMLF'     | 'IND'    | 'CV-33I0MZ00'(!)           = ''              | ''                 | 'CV-33I0MZ00'              |'L_MMD12FD'| '3.3UH/18A'                    | 'DISCRETE' | 'IND SMD 3.3UH 20% 18A MMD-12FD-3R3M-V1Q'       | 'CHIP'         | ''          | ''   | '20130805'  
 '3.3UH/18A'                    | 'SMLF'     | 'EMPTY'  | 'CV-33I0MZ00'(!)           = ''              | ''                 | 'CV-33I0MZ00'              |'L_MMD12FD'| 'NA'                           | 'IO'       | 'IND SMD 3.3UH 20% 18A MMD-12FD-3R3M-V1Q'       | 'CHIP'         | ''          | ''   | '20130805'  
 '4.7UH/13.5A'                  | 'SMLF'     | 'IND'    | 'CV-47D5MZ00'(!)           = ''              | ''                 | 'CV-47D5MZ00'              |'L_MMD12FD'| '4.7UH/13.5A'                  | 'DISCRETE' | 'IND SMD 4.7UH20% 13.5A MMD-12FD-4R7M-V1Q'      | 'CHIP'         | ''          | ''   | '20130805'  
 '4.7UH/13.5A'                  | 'SMLF'     | 'EMPTY'  | 'CV-47D5MZ00'(!)           = ''              | ''                 | 'CV-47D5MZ00'              |'L_MMD12FD'| 'NA'                           | 'IO'       | 'IND SMD 4.7UH20% 13.5A MMD-12FD-4R7M-V1Q'      | 'CHIP'         | ''          | ''   | '20130805'  
 '1.0UH/18A'                    | 'SMLF'     | 'IND'    | 'CV-10I0MZ01'(!)           = ''              | ''                 | 'CV-10I0MZ01'              |'L_PCMC104T'| '1.0UH/18A'                    | 'DISCRETE' | 'IND SMD 1.0UH +-20% 18A(PCMC104T-1R0MN)'       | 'CHIP'         | ''          | ''   | '20130806'  
 '1.0UH/18A'                    | 'SMLF'     | 'EMPTY'  | 'CV-10I0MZ01'(!)           = ''              | ''                 | 'CV-10I0MZ01'              |'L_PCMC104T'| 'NA'                           | 'IO'       | 'IND SMD 1.0UH +-20% 18A(PCMC104T-1R0MN)'       | 'CHIP'         | ''          | ''   | '20130806'  
 '28F0181-1SR-10/10A'           | 'SMLF'     | 'IND'    | 'CX11SR10000'(!)           = ''              | ''                 | 'CX11SR10000'              |'L_28F0181-1SR-10'| '28F0181-1SR-10/10A'           | 'DISCRETE' | 'EMI FILTER BEAD 28F0181-1SR-10 (115,10A)'      | 'CHIP'         | ''          | ''   | '20130828'  
 '28F0181-1SR-10/10A'           | 'SMLF'     | 'EMPTY'  | 'CX11SR10000'(!)           = ''              | ''                 | 'CX11SR10000'              |'L_28F0181-1SR-10'| 'NA'                           | 'IO'       | 'EMI FILTER BEAD 28F0181-1SR-10 (115,10A)'      | 'CHIP'         | ''          | ''   | '20130828'  
 '360NH/53A'                    | 'SMLF'     | 'IND'    | 'CV+36^0KZ02'(!)           = ''              | ''                 | 'CV+36^0KZ02'              |'L_HCUV138795L-271'| '360NH/53A'                    | 'DISCRETE' | 'IND SMD 360NH +-10% 53A(HCUV138795L-361'       | 'CHIP'         | ''          | ''   | '20131009'  
 '360NH/53A'                    | 'SMLF'     | 'EMPTY'  | 'CV+36^0KZ02'(!)           = ''              | ''                 | 'CV+36^0KZ02'              |'L_HCUV138795L-271'| 'NA'                           | 'IO'       | 'IND SMD 360NH +-10% 53A(HCUV138795L-361'       | 'CHIP'         | ''          | ''   | '20131009'  
 '470NH/40A'                    | 'SMLF'     | 'IND'    | 'CV+47^0KZ04'(!)           = ''              | ''                 | 'CV+47^0KZ04'              |'L_HCUV138795L-271'| '470NH/40A'                    | 'DISCRETE' | 'IND SMD 470NH +-10% 40A(HCUV138795L-471'       | 'CHIP'         | ''          | ''   | '20131009'  
 '470NH/40A'                    | 'SMLF'     | 'EMPTY'  | 'CV+47^0KZ04'(!)           = ''              | ''                 | 'CV+47^0KZ04'              |'L_HCUV138795L-271'| 'NA'                           | 'IO'       | 'IND SMD 470NH +-10% 40A(HCUV138795L-471'       | 'CHIP'         | ''          | ''   | '20131009'  
 'BLM18KG260TN1D/6A'            | 'SMLF'     | 'IND'    | 'CX8KG260000'(!)           = ''              | ''                 | 'CX8KG260000'              |'L0603'| 'BLM18KG260TN1D/6A'            | 'DISCRETE' | 'EMI FILTER BLM18KG260TN1D(26,6A)'              | 'CHIP'         | ''          | ''   | '20131016'  
 'BLM18KG260TN1D/6A'            | 'SMLF'     | 'EMPTY'  | 'CX8KG260000'(!)           = ''              | ''                 | 'CX8KG260000'              |'L0603'| 'NA'                           | 'IO'       | 'EMI FILTER BLM18KG260TN1D(26,6A)'              | 'CHIP'         | ''          | ''   | '20131016'  
 'BLM18KG601SN1D/1.3A'          | 'SMLF'     | 'IND'    | 'CX8KG601000'(!)           = 'End of Design' | 'Comp-Approve'     | 'CX8KG601000'              |'L0603'| 'BLM18KG601SN1D/1.3A'          | 'DISCRETE' | 'EMI FILTER BLM18KG601SN1D(600,1.3A)'           | 'CHIP'         | ''          | ''   | '20131016'  
 'BLM18KG601SN1D/1.3A'          | 'SMLF'     | 'EMPTY'  | 'CX8KG601000'(!)           = 'End of Design' | 'Comp-Approve'     | 'CX8KG601000'              |'L0603'| 'NA'                           | 'IO'       | 'EMI FILTER BLM18KG601SN1D(600,1.3A)'           | 'CHIP'         | ''          | ''   | '20131016'  
 'BLM18EG121SN1D/2A'            | 'SMLF'     | 'IND'    | 'CX8EG121000'(!)           = ''              | ''                 | 'CX8EG121000'              |'L0603'| 'BLM18EG121SN1D/2A'            | 'DISCRETE' | 'EMI FILTER BLM18EG121SN1D(120.2A)'             | 'CHIP'         | ''          | ''   | '20131016'  
 'BLM18EG121SN1D/2A'            | 'SMLF'     | 'EMPTY'  | 'CX8EG121000'(!)           = ''              | ''                 | 'CX8EG121000'              |'L0603'| 'NA'                           | 'IO'       | 'EMI FILTER BLM18EG121SN1D(120.2A)'             | 'CHIP'         | ''          | ''   | '20131016'  
 'HCB1608KF-471T10'             | 'SMLF'     | 'IND'    | 'CX471T10000'(!)           = ''              | ''                 | 'CX471T10000'              |'L0603'| 'HCB1608KF-471T10'             | 'DISCRETE' | 'EMI FILTER HCB1608KF-471T10(470,1000MA)'       | 'CHIP'         | ''          | ''   | '20131017'  
 'HCB1608KF-471T10'             | 'SMLF'     | 'EMPTY'  | 'CX471T10000'(!)           = ''              | ''                 | 'CX471T10000'              |'L0603'| 'NA'                           | 'IO'       | 'EMI FILTER HCB1608KF-471T10(470,1000MA)'       | 'CHIP'         | ''          | ''   | '20131017'  
 'PBY160808T-181Y-N/2000MA'     | 'SMLF'     | 'IND'    | 'CX08T181002'(!)           = ''              | ''                 | 'CX08T181002'              |'L0603'| 'PBY160808T-181Y-N/2000MA'     | 'DISCRETE' | 'EMI FILTER PBY160808T-181Y-N(180,2000MA)'      | 'CHIP'         | ''          | ''   | '20131029'  
 'PBY160808T-181Y-N/2000MA'     | 'SMLF'     | 'EMPTY'  | 'CX08T181002'(!)           = ''              | ''                 | 'CX08T181002'              |'L0603'| 'NA'                           | 'IO'       | 'EMI FILTER PBY160808T-181Y-N(180,2000MA)'      | 'CHIP'         | ''          | ''   | '20131029'  
 '2.2UH/790MA'                  | 'SMLF'     | 'IND'    | 'CV-2208MZ01'(!)           = ''              | ''                 | 'CV-2208MZ01'              |'L1210XC'| '2.2UH/790MA'                  | 'DISCRETE' | 'IND SMD 2.2UH 20% 790MA(LQH32CN2R2M33L)'       | 'CHIP'         | ''          | ''   | '20131021'  
 '2.2UH/790MA'                  | 'SMLF'     | 'EMPTY'  | 'CV-2208MZ01'(!)           = ''              | ''                 | 'CV-2208MZ01'              |'L1210XC'| 'NA'                           | 'IO'       | 'IND SMD 2.2UH 20% 790MA(LQH32CN2R2M33L)'       | 'CHIP'         | ''          | ''   | '20131021'  
 '0.45UF/25A'                   | 'SMLF'     | 'IND'    | 'CV+45Q0MZ02'(!)           = ''              | ''                 | 'CV+45Q0MZ02'              |'L_MMD-10DZ-R45M-X2Q'| '0.45UF/25A'                   | 'DISCRETE' | 'IND 0.45U +-20% 25A(MMD-10DZ-R45M-X2Q)'        | 'CHIP'         | ''          | ''   | '20131105'  
 '0.45UF/25A'                   | 'SMLF'     | 'EMPTY'  | 'CV+45Q0MZ02'(!)           = ''              | ''                 | 'CV+45Q0MZ02'              |'L_MMD-10DZ-R45M-X2Q'| 'NA'                           | 'IO'       | 'IND 0.45U +-20% 25A(MMD-10DZ-R45M-X2Q)'        | 'CHIP'         | ''          | ''   | '20131105'  
 '180NH/75A'                    | 'SMLF'     | 'IND'    | 'CV+18^0KZ03'(!)           = ''              | ''                 | 'CV+18^0KZ03'              |'L_HCUV117595'| '180NH/75A'                    | 'DISCRETE' | 'IND SMD 180NH +-10% 75A(HCUV117595-181B)'      | 'CHIP'         | ''          | ''   | '20131204'  
 '180NH/75A'                    | 'SMLF'     | 'EMPTY'  | 'CV+18^0KZ03'(!)           = ''              | ''                 | 'CV+18^0KZ03'              |'L_HCUV117595'| 'NA'                           | 'IO'       | 'IND SMD 180NH +-10% 75A(HCUV117595-181B)'      | 'CHIP'         | ''          | ''   | '20131204'  
 'FCM2012KF-601T/0.5A'          | 'SMLF'     | 'IND'    | 'CX601T05003'(!)           = ''              | ''                 | 'CX601T05003'              |'L0805'| 'FCM2012KF-601T/0.5A'          | 'DISCRETE' | 'EMI FILTER FCM2012KF-601T05(600,0.5A)'         | 'CHIP'         | ''          | ''   | '20131206'  
 'FCM2012KF-601T/0.5A'          | 'SMLF'     | 'EMPTY'  | 'CX601T05003'(!)           = ''              | ''                 | 'CX601T05003'              |'L0805'| 'NA'                           | 'IO'       | 'EMI FILTER FCM2012KF-601T05(600,0.5A)'         | 'CHIP'         | ''          | ''   | '20131206'  
 '3.3UH/4A'                     | 'SMLF'     | 'IND'    | 'CV-3340MZ01'(!)           = ''              | ''                 | 'CV-3340MZ01'              |'L_PCMB042T'| '3.3UH/4A'                     | 'DISCRETE' | 'IND SMD 3.3UH +-20% 4A PIMB042T-3R3MS'         | 'CHIP'         | ''          | ''   | '20131211'  
 '3.3UH/4A'                     | 'SMLF'     | 'EMPTY'  | 'CV-3340MZ01'(!)           = ''              | ''                 | 'CV-3340MZ01'              |'L_PCMB042T'| 'NA'                           | 'IO'       | 'IND SMD 3.3UH +-20% 4A PIMB042T-3R3MS'         | 'CHIP'         | ''          | ''   | '20131211'  
 '6.8UH/2.8A'                   | 'SMLF'     | 'IND'    | 'CV-6828MZ02'(!)           = ''              | ''                 | 'CV-6828MZ02'              |'L_MMD-05AH'| '6.8UH/2.8A'                   | 'DISCRETE' | 'IND SMD 6.8UH+-20%2.8A MMD-05AH-6R8M-X2Q'      | 'CHIP'         | ''          | ''   | '20131211'  
 '6.8UH/2.8A'                   | 'SMLF'     | 'EMPTY'  | 'CV-6828MZ02'(!)           = ''              | ''                 | 'CV-6828MZ02'              |'L_MMD-05AH'| 'NA'                           | 'IO'       | 'IND SMD 6.8UH+-20%2.8A MMD-05AH-6R8M-X2Q'      | 'CHIP'         | ''          | ''   | '20131211'  
 '1.0UH/9A'                     | 'SMLF'     | 'IND'    | 'CV-1090MZ00'(!)           = ''              | ''                 | 'CV-1090MZ00'              |'L_PCMB062D'| '1.0UH/9A'                     | 'DISCRETE' | 'IND SMD 1.0UH +-20% 9A(PCMB062D-1R0MS)'        | 'CHIP'         | ''          | ''   | '20131211'  
 '1.0UH/9A'                     | 'SMLF'     | 'EMPTY'  | 'CV-1090MZ00'(!)           = ''              | ''                 | 'CV-1090MZ00'              |'L_PCMB062D'| 'NA'                           | 'IO'       | 'IND SMD 1.0UH +-20% 9A(PCMB062D-1R0MS)'        | 'CHIP'         | ''          | ''   | '20131211'  
 '1.5UH/6A'                     | 'SMLF'     | 'IND'    | 'CV-1560MZ01'(!)           = ''              | ''                 | 'CV-1560MZ01'              |'L_CMME053T_4-5X4-7'| '1.5UH/6A'                     | 'DISCRETE' | 'IND SMD 1.5UH +-20% 6A(PCMB053T-1R5MS)'        | 'CHIP'         | ''          | ''   | '20131213'  
 '1.5UH/6A'                     | 'SMLF'     | 'EMPTY'  | 'CV-1560MZ01'(!)           = ''              | ''                 | 'CV-1560MZ01'              |'L_CMME053T_4-5X4-7'| 'NA'                           | 'IO'       | 'IND SMD 1.5UH +-20% 6A(PCMB053T-1R5MS)'        | 'CHIP'         | ''          | ''   | '20131213'  
 '2.2UH/7A'                     | 'SMLF'     | 'IND'    | 'CV-2270MZ05'(!)           = ''              | ''                 | 'CV-2270MZ05'              |'L_PCMB062D'| '2.2UH/7A'                     | 'DISCRETE' | 'IND SMD 2.2UH +-20% 7A PCMB062D-2R2MS'         | 'CHIP'         | ''          | ''   | '20131217'  
 '2.2UH/7A'                     | 'SMLF'     | 'EMPTY'  | 'CV-2270MZ05'(!)           = ''              | ''                 | 'CV-2270MZ05'              |'L_PCMB062D'| 'NA'                           | 'IO'       | 'IND SMD 2.2UH +-20% 7A PCMB062D-2R2MS'         | 'CHIP'         | ''          | ''   | '20131217'  
 '3.3UH/13A'                    | 'SMLF'     | 'IND'    | 'CV-33D0MZ01'(!)           = ''              | ''                 | 'CV-33D0MZ01'              |'L_PCMB062D'| '3.3UH/13A'                    | 'DISCRETE' | 'IND SMD 3.3UH +-20% 13A(PCMB062D-3R3MS)'       | 'CHIP'         | ''          | ''   | '20131217'  
 '3.3UH/13A'                    | 'SMLF'     | 'EMPTY'  | 'CV-33D0MZ01'(!)           = ''              | ''                 | 'CV-33D0MZ01'              |'L_PCMB062D'| 'NA'                           | 'IO'       | 'IND SMD 3.3UH +-20% 13A(PCMB062D-3R3MS)'       | 'CHIP'         | ''          | ''   | '20131217'  
 '2.2UH/22A'                    | 'SMLF'     | 'IND'    | 'CV-22M0MZ01'(!)           = ''              | ''                 | 'CV-22M0MZ01'              |'L_PCMS136E'| '2.2UH/22A'                    | 'DISCRETE' | 'IND SMD 2.2UH +-20% 22A PCMS136E-2R2MF'        | 'CHIP'         | ''          | ''   | '20140114'  
 '2.2UH/22A'                    | 'SMLF'     | 'EMPTY'  | 'CV-22M0MZ01'(!)           = ''              | ''                 | 'CV-22M0MZ01'              |'L_PCMS136E'| 'NA'                           | 'IO'       | 'IND SMD 2.2UH +-20% 22A PCMS136E-2R2MF'        | 'CHIP'         | ''          | ''   | '20140114'  
 '3.3UH/19A'                    | 'SMLF'     | 'IND'    | 'CV-33J0MZ00'(!)           = ''              | ''                 | 'CV-33J0MZ00'              |'L_PCMS136E'| '3.3UH/19A'                    | 'DISCRETE' | 'IND SMD 3.3UH +-20% 19A PCMS136E-3R3MF'        | 'CHIP'         | ''          | ''   | '20140114'  
 '3.3UH/19A'                    | 'SMLF'     | 'EMPTY'  | 'CV-33J0MZ00'(!)           = ''              | ''                 | 'CV-33J0MZ00'              |'L_PCMS136E'| 'NA'                           | 'IO'       | 'IND SMD 3.3UH +-20% 19A PCMS136E-3R3MF'        | 'CHIP'         | ''          | ''   | '20140114'  
 '6.8UH/11.5A'                  | 'SMLF'     | 'IND'    | 'CV-68B5MZ00'(!)           = ''              | ''                 | 'CV-68B5MZ00'              |'L_MMD12FD'| '6.8UH/11.5A'                  | 'DISCRETE' | 'IND SMD 6.8UH +-20% 11.5A MMD-12FD-6R8M'       | 'CHIP'         | ''          | ''   | '20140205'  
 '6.8UH/11.5A'                  | 'SMLF'     | 'EMPTY'  | 'CV-68B5MZ00'(!)           = ''              | ''                 | 'CV-68B5MZ00'              |'L_MMD12FD'| 'NA'                           | 'IO'       | 'IND SMD 6.8UH +-20% 11.5A MMD-12FD-6R8M'       | 'CHIP'         | ''          | ''   | '20140205'  
 '0.1UH/11.5A'                  | 'SMLF'     | 'IND'    | 'CV+1012MZ00'(!)           = ''              | ''                 | 'CV+1012MZ00'              |'L_MMD-04AB'| '0.1UH/11.5A'                  | 'DISCRETE' | 'IND SMD 0.1UH 20% 11.5A MMD-04AB-R10M-V1'      | 'CHIP'         | ''          | ''   | '20140205'  
 '0.1UH/11.5A'                  | 'SMLF'     | 'EMPTY'  | 'CV+1012MZ00'(!)           = ''              | ''                 | 'CV+1012MZ00'              |'L_MMD-04AB'| 'NA'                           | 'IO'       | 'IND SMD 0.1UH 20% 11.5A MMD-04AB-R10M-V1'      | 'CHIP'         | ''          | ''   | '20140205'  
 '4.7UH/8A'                     | 'SMLF'     | 'IND'    | 'CV-4780MZ04'(!)           = ''              | ''                 | 'CV-4780MZ04'              |'L_MMD-08DZ'| '4.7UH/8A'                     | 'DISCRETE' | 'IND SMD 4.7UH 20% 8A MMD-08DZ-4R7M-V2Q'        | 'CHIP'         | ''          | ''   | '20140205'  
 '4.7UH/8A'                     | 'SMLF'     | 'EMPTY'  | 'CV-4780MZ04'(!)           = ''              | ''                 | 'CV-4780MZ04'              |'L_MMD-08DZ'| 'NA'                           | 'IO'       | 'IND SMD 4.7UH 20% 8A MMD-08DZ-4R7M-V2Q'        | 'CHIP'         | ''          | ''   | '20140205'  
 '7.3UH/12A'                    | 'SMLF'     | 'IND'    | 'CV-73C0MZ00'(!)           = ''              | ''                 | 'CV-73C0MZ00'              |'L_HAH1378'| '7.3UH/12A'                    | 'DISCRETE' | 'IND SMD 7.3UH +-20% 12A(HAH1378-7R3)'          | 'CHIP'         | ''          | ''   | '20140205'  
 '7.3UH/12A'                    | 'SMLF'     | 'EMPTY'  | 'CV-73C0MZ00'(!)           = ''              | ''                 | 'CV-73C0MZ00'              |'L_HAH1378'| 'NA'                           | 'IO'       | 'IND SMD 7.3UH +-20% 12A(HAH1378-7R3)'          | 'CHIP'         | ''          | ''   | '20140205'  
 '1.5UH/13.3A'                  | 'SMLF'     | 'IND'    | 'CV-15D3MZ00'(!)           = ''              | ''                 | 'CV-15D3MZ00'              |'L_HAH85'| '1.5UH/13.3A'                  | 'DISCRETE' | 'IND SMD 1.5UH +-20% 13.3A(HAH85-1R5)'          | 'CHIP'         | ''          | ''   | '20140205'  
 '1.5UH/13.3A'                  | 'SMLF'     | 'EMPTY'  | 'CV-15D3MZ00'(!)           = ''              | ''                 | 'CV-15D3MZ00'              |'L_HAH85'| 'NA'                           | 'IO'       | 'IND SMD 1.5UH +-20% 13.3A(HAH85-1R5)'          | 'CHIP'         | ''          | ''   | '20140205'  
 '0.15UH/36A'                   | 'SMLF'     | 'IND'    | 'CV+15^0MZ07'(!)           = ''              | ''                 | 'CV+15^0MZ07'              |'L_PCME064T'| '0.15UH/36A'                   | 'DISCRETE' | 'IND SMD0.15U20%,36A(PCME064T-R15MS0R667)'      | 'CHIP'         | ''          | ''   | '20140218'  
 '0.15UH/36A'                   | 'SMLF'     | 'EMPTY'  | 'CV+15^0MZ07'(!)           = ''              | ''                 | 'CV+15^0MZ07'              |'L_PCME064T'| 'NA'                           | 'IO'       | 'IND SMD0.15U20%,36A(PCME064T-R15MS0R667)'      | 'CHIP'         | ''          | ''   | '20140218'  
 '470NH/25A'                    | 'SMLF'     | 'IND'    | 'CV+47Q0KZ00'(!)           = ''              | ''                 | 'CV+47Q0KZ00'              |'L_HCUVD6595-471'| '470NH/25A'                    | 'DISCRETE' | 'IND SMD 470NH +-10% 25A(HCUVD6595-471)'        | 'CHIP'         | ''          | ''   | '20140312'  
 '470NH/25A'                    | 'SMLF'     | 'EMPTY'  | 'CV+47Q0KZ00'(!)           = ''              | ''                 | 'CV+47Q0KZ00'              |'L_HCUVD6595-471'| 'NA'                           | 'IO'       | 'IND SMD 470NH +-10% 25A(HCUVD6595-471)'        | 'CHIP'         | ''          | ''   | '20140312'  
 'BLM15AG601SN1D/300MA'         | 'SMLF'     | 'IND'    | 'CX5AG601004'(!)           = ''              | ''                 | 'CX5AG601004'              |'L0402'| 'BLM15AG601SN1D/300MA'         | 'DISCRETE' | 'EMI FILTER BLM15AG601SN1D(600.300MA)'          | 'CHIP'         | ''          | ''   | '20140416'  
 'BLM15AG601SN1D/300MA'         | 'SMLF'     | 'EMPTY'  | 'CX5AG601004'(!)           = ''              | ''                 | 'CX5AG601004'              |'L0402'| 'NA'                           | 'IO'       | 'EMI FILTER BLM15AG601SN1D(600.300MA)'          | 'CHIP'         | ''          | ''   | '20140416'  
 '220NH/45A'                    | 'SMLF'     | 'IND'    | 'CV+22^0KZ03'(!)           = ''              | ''                 | 'CV+22^0KZ03'              |'L_HCUV117595'| '220NH/45A'                    | 'DISCRETE' | 'IND SMD 220NH +-10% 45A(HCUV117595-221A)'      | 'CHIP'         | ''          | ''   | '20140424'  
 '220NH/45A'                    | 'SMLF'     | 'EMPTY'  | 'CV+22^0KZ03'(!)           = ''              | ''                 | 'CV+22^0KZ03'              |'L_HCUV117595'| 'NA'                           | 'IO'       | 'IND SMD 220NH +-10% 45A(HCUV117595-221A)'      | 'CHIP'         | ''          | ''   | '20140424'  
 '0.47UH/63A'                   | 'SMLF'     | 'IND'    | 'CV+47^0MZ08'(!)           = ''              | ''                 | 'CV+47^0MZ08'              |'L_MMD12FD'| '0.47UH/63A'                   | 'DISCRETE' | 'IND SMD 0.47UH 20% 63A MMD-12FD-R47M-V1Q'      | 'CHIP'         | ''          | ''   | '20140428'  
 '0.47UH/63A'                   | 'SMLF'     | 'EMPTY'  | 'CV+47^0MZ08'(!)           = ''              | ''                 | 'CV+47^0MZ08'              |'L_MMD12FD'| 'NA'                           | 'IO'       | 'IND SMD 0.47UH 20% 63A MMD-12FD-R47M-V1Q'      | 'CHIP'         | ''          | ''   | '20140428'  
 'HCB2012KF-800T50/5A'          | 'SMLF'     | 'IND'    | 'CX000800506'(!)           = ''              | ''                 | 'CX000800506'              |'L0805'| 'HCB2012KF-800T50/5A'          | 'DISCRETE' | 'EMI FILTER CHIP HCB2012KF800T50(80,5A)'        | 'CHIP'         | ''          | ''   | '20140430'  
 'HCB2012KF-800T50/5A'          | 'SMLF'     | 'EMPTY'  | 'CX000800506'(!)           = ''              | ''                 | 'CX000800506'              |'L0805'| 'NA'                           | 'IO'       | 'EMI FILTER CHIP HCB2012KF800T50(80,5A)'        | 'CHIP'         | ''          | ''   | '20140430'  
 'HCB2012VF-800T50/5A'          | 'SMLF'     | 'IND'    | 'CX800T50000'(!)           = ''              | ''                 | 'CX800T50000'              |'L0805'| 'HCB2012VF-800T50/5A'          | 'DISCRETE' | 'EMI FILTER CHIP HCB2012VF-800T50(80,5A)'       | 'CHIP'         | ''          | ''   | '20140430'  
 'HCB2012VF-800T50/5A'          | 'SMLF'     | 'EMPTY'  | 'CX800T50000'(!)           = ''              | ''                 | 'CX800T50000'              |'L0805'| 'NA'                           | 'IO'       | 'EMI FILTER CHIP HCB2012VF-800T50(80,5A)'       | 'CHIP'         | ''          | ''   | '20140430'  
 'MHC2012S800UBP/5A'            | 'SMLF'     | 'IND'    | 'CX12S800000'(!)           = ''              | ''                 | 'CX12S800000'              |'L0805'| 'MHC2012S800UBP/5A'            | 'DISCRETE' | 'EMI FILTER MHC2012S800UBP(80,5A)'              | 'CHIP'         | ''          | ''   | '20140430'  
 'MHC2012S800UBP/5A'            | 'SMLF'     | 'EMPTY'  | 'CX12S800000'(!)           = ''              | ''                 | 'CX12S800000'              |'L0805'| 'NA'                           | 'IO'       | 'EMI FILTER MHC2012S800UBP(80,5A)'              | 'CHIP'         | ''          | ''   | '20140430'  
 '22UH/5A'                      | 'SMLF'     | 'IND'    | 'CV02250MZ01'(!)           = ''              | ''                 | 'CV02250MZ01'              |'L_PCMB104TXB'| '22UH/5A'                      | 'DISCRETE' | 'IND SMD 22UH+-20% 5A(PCMB104T-220MS)'          | 'CHIP'         | ''          | ''   | '20140508'  
 '22UH/5A'                      | 'SMLF'     | 'EMPTY'  | 'CV02250MZ01'(!)           = ''              | ''                 | 'CV02250MZ01'              |'L_PCMB104TXB'| 'NA'                           | 'IO'       | 'IND SMD 22UH+-20% 5A(PCMB104T-220MS)'          | 'CHIP'         | ''          | ''   | '20140508'  
 '10UH/4A'                      | 'SMLF'     | 'IND'    | 'CV01040MZ02'(!)           = ''              | ''                 | 'CV01040MZ02'              |'L_PCMB063T'| '10UH/4A'                      | 'DISCRETE' | 'IND SMD 10UH +-20%,4A(PCMB063T-100MS)'         | 'CHIP'         | ''          | ''   | '20140523'  
 '10UH/4A'                      | 'SMLF'     | 'EMPTY'  | 'CV01040MZ02'(!)           = ''              | ''                 | 'CV01040MZ02'              |'L_PCMB063T'| 'NA'                           | 'IO'       | 'IND SMD 10UH +-20%,4A(PCMB063T-100MS)'         | 'CHIP'         | ''          | ''   | '20140523'  
 '220NH/45A'                    | 'SMLF'     | 'IND'    | 'CV+22^0KZ08'(!)           = ''              | ''                 | 'CV+22^0KZ08'              |'L_HCUV117595'| '220NH/45A'                    | 'DISCRETE' | 'IND SMD 220NH +-10% 45A(HCUV117595-221B)'      | 'CHIP'         | ''          | ''   | '20140623'  
 '220NH/45A'                    | 'SMLF'     | 'EMPTY'  | 'CV+22^0KZ08'(!)           = ''              | ''                 | 'CV+22^0KZ08'              |'L_HCUV117595'| 'NA'                           | 'IO'       | 'IND SMD 220NH +-10% 45A(HCUV117595-221B)'      | 'CHIP'         | ''          | ''   | '20140623'  
 '195NH/45A'                    | 'SMLF'     | 'IND'    | 'CV+19^0KZ00'(!)           = ''              | ''                 | 'CV+19^0KZ00'              |'L_HCUV117595'| '195NH/45A'                    | 'DISCRETE' | 'IND SMD 195NH +-10% 45A(HCUV117595-201)'       | 'CHIP'         | ''          | ''   | '20140702'  
 '195NH/45A'                    | 'SMLF'     | 'EMPTY'  | 'CV+19^0KZ00'(!)           = ''              | ''                 | 'CV+19^0KZ00'              |'L_HCUV117595'| 'NA'                           | 'IO'       | 'IND SMD 195NH +-10% 45A(HCUV117595-201)'       | 'CHIP'         | ''          | ''   | '20140702'  
 '0.45UH/45A'                   | 'SMLF'     | 'IND'    | 'CV+45^0MZ09'(!)           = 'Non-Preferred' | 'End of Life'      | 'CV+45^0MZ09'              |'L_L30909-4_EOL'| '0.45UH/45A'                   | 'DISCRETE' | 'IND SMD 0.45UH, +-20%, 45A(L30909-4)'          | 'CHIP'         | ''          | ''   | '20140702'  
 '0.45UH/45A'                   | 'SMLF'     | 'EMPTY'  | 'CV+45^0MZ09'(!)           = 'Non-Preferred' | 'End of Life'      | 'CV+45^0MZ09'              |'L_L30909-4_EOL'| 'NA'                           | 'IO'       | 'IND SMD 0.45UH, +-20%, 45A(L30909-4)'          | 'CHIP'         | ''          | ''   | '20140702'  
 '1UH/2.7A'                     | 'SMLF'     | 'IND'    | 'CV-1027MZ03'(!)           = ''              | ''                 | 'CV-1027MZ03'              |'L_DFP252012TF_2-5X2'| '1UH/2.7A'                     | 'DISCRETE' | 'IND SMD 1U 20%2.7A(DFP252012TF-1R0M-2A7)'      | 'CHIP'         | ''          | ''   | '20140709'  
 '1UH/2.7A'                     | 'SMLF'     | 'EMPTY'  | 'CV-1027MZ03'(!)           = ''              | ''                 | 'CV-1027MZ03'              |'L_DFP252012TF_2-5X2'| 'NA'                           | 'IO'       | 'IND SMD 1U 20%2.7A(DFP252012TF-1R0M-2A7)'      | 'CHIP'         | ''          | ''   | '20140709'  
 'HCB1608KF-221T20/2000MA'      | 'SMLF'     | 'IND'    | 'CX221T20001'(!)           = ''              | ''                 | 'CX221T20001'              |'L0603'| 'HCB1608KF-221T20/2000MA'      | 'DISCRETE' | 'EMI FILTER HCB1608KF-221T20(220,2000MA)'       | 'CHIP'         | ''          | ''   | '20140711'  
 'HCB1608KF-221T20/2000MA'      | 'SMLF'     | 'EMPTY'  | 'CX221T20001'(!)           = ''              | ''                 | 'CX221T20001'              |'L0603'| 'NA'                           | 'IO'       | 'EMI FILTER HCB1608KF-221T20(220,2000MA)'       | 'CHIP'         | ''          | ''   | '20140711'  
 '270NH/32A'                    | 'SMLF'     | 'IND'    | 'CV+27X0KZ00'(!)           = ''              | ''                 | 'CV+27X0KZ00'              |'L_HCUV106411-401G'| '270NH/32A'                    | 'DISCRETE' | 'IND SMD 270NH +-10% 32A(HCUV106411-271)'       | 'CHIP'         | ''          | ''   | '20140714'  
 '270NH/32A'                    | 'SMLF'     | 'EMPTY'  | 'CV+27X0KZ00'(!)           = ''              | ''                 | 'CV+27X0KZ00'              |'L_HCUV106411-401G'| 'NA'                           | 'IO'       | 'IND SMD 270NH +-10% 32A(HCUV106411-271)'       | 'CHIP'         | ''          | ''   | '20140714'  
 '1.5UH/6A'                     | 'SMLF'     | 'IND'    | 'CV-1560MZ00'(!)           = ''              | ''                 | 'CV-1560MZ00'              |'L_MMD-05CZ-2R2M-X1Q'| '1.5UH/6A'                     | 'DISCRETE' | 'IND SMD 1.5UH 20% 6A MMD-05CZ-1R5M-X1Q'        | 'CHIP'         | ''          | ''   | '20140714'  
 '1.5UH/6A'                     | 'SMLF'     | 'EMPTY'  | 'CV-1560MZ00'(!)           = ''              | ''                 | 'CV-1560MZ00'              |'L_MMD-05CZ-2R2M-X1Q'| 'NA'                           | 'IO'       | 'IND SMD 1.5UH 20% 6A MMD-05CZ-1R5M-X1Q'        | 'CHIP'         | ''          | ''   | '20140714'  
 '195NH/61A'                    | 'SMLF'     | 'IND'    | 'CV+19^0KZ01'(!)           = ''              | ''                 | 'CV+19^0KZ01'              |'L_FP1110V1_10-7X7-5'| '195NH/61A'                    | 'DISCRETE' | 'IND SMD 195NH +-10% 61A(FP1110V1-R20-R)'       | 'CHIP'         | ''          | ''   | '20140717'  
 '195NH/61A'                    | 'SMLF'     | 'EMPTY'  | 'CV+19^0KZ01'(!)           = ''              | ''                 | 'CV+19^0KZ01'              |'L_FP1110V1_10-7X7-5'| 'NA'                           | 'IO'       | 'IND SMD 195NH +-10% 61A(FP1110V1-R20-R)'       | 'CHIP'         | ''          | ''   | '20140717'  
 '1000UH/0.08A'                 | 'SMLF'     | 'IND'    | 'CV21001MZ00'(!)           = ''              | ''                 | 'CV21001MZ00'              |'L_LPS5015'| '1000UH/0.08A'                 | 'DISCRETE' | 'IND SMD 1000UH +-20% 0.08A LPS5015-105ML'      | 'CHIP'         | ''          | ''   | '20140731'  
 '1000UH/0.08A'                 | 'SMLF'     | 'EMPTY'  | 'CV21001MZ00'(!)           = ''              | ''                 | 'CV21001MZ00'              |'L_LPS5015'| 'NA'                           | 'IO'       | 'IND SMD 1000UH +-20% 0.08A LPS5015-105ML'      | 'CHIP'         | ''          | ''   | '20140731'  
 '0.8UH/66A'                    | 'SMLF'     | 'IND'    | 'CV+80^0KZ00'(!)           = ''              | ''                 | 'CV+80^0KZ00'              |'L_HCBD141312'| '0.8UH/66A'                    | 'DISCRETE' | 'IND SMD 0.8UH +-10% 66A(HCBD141312-801)'       | 'CHIP'         | ''          | ''   | '20140801'  
 '0.8UH/66A'                    | 'SMLF'     | 'EMPTY'  | 'CV+80^0KZ00'(!)           = ''              | ''                 | 'CV+80^0KZ00'              |'L_HCBD141312'| 'NA'                           | 'IO'       | 'IND SMD 0.8UH +-10% 66A(HCBD141312-801)'       | 'CHIP'         | ''          | ''   | '20140801'  
 '0.1UH/11.5A'                  | 'SMLF'     | 'IND'    | 'CV+10B5MZ00'(!)           = 'End of Design' | 'Comp-Approve'     | 'CV+10B5MZ00'              |'L_IHLP1616AB_4-45X4-06'| '0.1UH/11.5A'                  | 'DISCRETE' | 'IND SMD 0.1U +-20% 11.5A(IHLP1616ABERR10'      | 'CHIP'         | ''          | ''   | '20140806'  
 '0.1UH/11.5A'                  | 'SMLF'     | 'EMPTY'  | 'CV+10B5MZ00'(!)           = 'End of Design' | 'Comp-Approve'     | 'CV+10B5MZ00'              |'L_IHLP1616AB_4-45X4-06'| 'NA'                           | 'IO'       | 'IND SMD 0.1U +-20% 11.5A(IHLP1616ABERR10'      | 'CHIP'         | ''          | ''   | '20140806'  
 'PBY160808T-221Y-N/2A'         | 'SMLF'     | 'IND'    | 'CX08T221000'(!)           = ''              | ''                 | 'CX08T221000'              |'L0603'| 'PBY160808T-221Y-N/2A'         | 'DISCRETE' | 'EMI FILTER PBY160808T-221Y-N(220,2A)'          | 'CHIP'         | ''          | ''   | '20140808'  
 'PBY160808T-221Y-N/2A'         | 'SMLF'     | 'EMPTY'  | 'CX08T221000'(!)           = ''              | ''                 | 'CX08T221000'              |'L0603'| 'NA'                           | 'IO'       | 'EMI FILTER PBY160808T-221Y-N(220,2A)'          | 'CHIP'         | ''          | ''   | '20140808'  
 '1UH/10A'                      | 'SMLF'     | 'IND'    | 'TV-10A0MZ00'(!)           = ''              | ''                 | 'TV-10A0MZ00'              |'L_GLMC_6-5X6-5'| '1UH/10A'                      | 'DISCRETE' | 'IND SMD 1UH +-20% 10A(GLMC1R003A)EMSSEL'       | 'CHIP'         | ''          | ''   | '20140808'  
 '1UH/10A'                      | 'SMLF'     | 'EMPTY'  | 'TV-10A0MZ00'(!)           = ''              | ''                 | 'TV-10A0MZ00'              |'L_GLMC_6-5X6-5'| 'NA'                           | 'IO'       | 'IND SMD 1UH +-20% 10A(GLMC1R003A)EMSSEL'       | 'CHIP'         | ''          | ''   | '20140808'  
 'BLM18PG121SN1D/2000MA'        | 'SMLF'     | 'IND'    | 'CX8PG121009'(!)           = ''              | ''                 | 'CX8PG121009'              |'L0603'| 'BLM18PG121SN1D/2000MA'        | 'DISCRETE' | 'EMI FILTER BLM18PG121SN(120,2000MA)'           | 'CHIP'         | ''          | ''   | '20140812'  
 'BLM18PG121SN1D/2000MA'        | 'SMLF'     | 'EMPTY'  | 'CX8PG121009'(!)           = ''              | ''                 | 'CX8PG121009'              |'L0603'| 'NA'                           | 'IO'       | 'EMI FILTER BLM18PG121SN(120,2000MA)'           | 'CHIP'         | ''          | ''   | '20140812'  
 'HCP0805-1R5-R/13.3A'          | 'SMLF'     | 'IND'    | 'CV-15D3MZ01'(!)           = ''              | ''                 | 'CV-15D3MZ01'              |'L_HCP0805_7-7X7-4'| 'HCP0805-1R5-R/13.3A'          | 'DISCRETE' | 'IND SMD 1.5UF +-20% 13.3A(HCP0805-1R5-R)'      | 'CHIP'         | ''          | ''   | '20140812'  
 'HCP0805-1R5-R/13.3A'          | 'SMLF'     | 'EMPTY'  | 'CV-15D3MZ01'(!)           = ''              | ''                 | 'CV-15D3MZ01'              |'L_HCP0805_7-7X7-4'| 'NA'                           | 'IO'       | 'IND SMD 1.5UF +-20% 13.3A(HCP0805-1R5-R)'      | 'CHIP'         | ''          | ''   | '20140812'  
 '4.7UH/8.7A'                   | 'SMLF'     | 'IND'    | 'CV-4787MZ00'(!)           = ''              | ''                 | 'CV-4787MZ00'              |'L_IHLP3232DZ_8-18X8-18'| '4.7UH/8.7A'                   | 'DISCRETE' | 'IND SMD 4.7U +-20% 8.7A(IHLP3232DZER4R7M'      | 'CHIP'         | ''          | ''   | '20140812'  
 '4.7UH/8.7A'                   | 'SMLF'     | 'EMPTY'  | 'CV-4787MZ00'(!)           = ''              | ''                 | 'CV-4787MZ00'              |'L_IHLP3232DZ_8-18X8-18'| 'NA'                           | 'IO'       | 'IND SMD 4.7U +-20% 8.7A(IHLP3232DZER4R7M'      | 'CHIP'         | ''          | ''   | '20140812'  
 '65NH/24A'                     | 'SMLF'     | 'IND'    | 'TVA65P0EZ00'(!)           = ''              | 'End of Life'      | 'TVA65P0EZ00'              |'L_59PR65_3-8X3-8_EOL'| '65NH/24A'                     | 'DISCRETE' | 'IND SMD 65NH +-15% 24A(59PR65-650)SELEMS'      | 'CHIP'         | ''          | ''   | '20140812'  
 '65NH/24A'                     | 'SMLF'     | 'EMPTY'  | 'TVA65P0EZ00'(!)           = ''              | 'End of Life'      | 'TVA65P0EZ00'              |'L_59PR65_3-8X3-8_EOL'| 'NA'                           | 'IO'       | 'IND SMD 65NH +-15% 24A(59PR65-650)SELEMS'      | 'CHIP'         | ''          | ''   | '20140812'  
 'BLM18PG331SN1D/1200MA'        | 'SMLF'     | 'IND'    | 'CX8PG331000'(!)           = ''              | ''                 | 'CX8PG331000'              |'L0603'| 'BLM18PG331SN1D/1200MA'        | 'DISCRETE' | 'EMI FILTER BLM18PG331SN1D(330,1200MA)'         | 'CHIP'         | ''          | ''   | '20140819'  
 'BLM18PG331SN1D/1200MA'        | 'SMLF'     | 'EMPTY'  | 'CX8PG331000'(!)           = ''              | ''                 | 'CX8PG331000'              |'L0603'| 'NA'                           | 'IO'       | 'EMI FILTER BLM18PG331SN1D(330,1200MA)'         | 'CHIP'         | ''          | ''   | '20140819'  
 'HCB2012KF-601T20/2000MA'      | 'SMLF'     | 'IND'    | 'CX601T20000'(!)           = ''              | ''                 | 'CX601T20000'              |'L0805'| 'HCB2012KF-601T20/2000MA'      | 'DISCRETE' | 'EMI FILTER HCB2012KF-601T20(600,2000MA)'       | 'CHIP'         | ''          | ''   | '20140820'  
 'HCB2012KF-601T20/2000MA'      | 'SMLF'     | 'EMPTY'  | 'CX601T20000'(!)           = ''              | ''                 | 'CX601T20000'              |'L0805'| 'NA'                           | 'IO'       | 'EMI FILTER HCB2012KF-601T20(600,2000MA)'       | 'CHIP'         | ''          | ''   | '20140820'  
 '57511/33A'                    | 'SMLF'     | 'IND'    | 'CV-47Y0TZ00'(!)           = ''              | ''                 | 'CV-47Y0TZ00'              |'L_57511_30X19-3'| '57511/33A'                    | 'DISCRETE' | 'IND SMD 4.7UF +15%-25% 33A(57511)'             | 'CHIP'         | ''          | ''   | '20140820'  
 '57511/33A'                    | 'SMLF'     | 'EMPTY'  | 'CV-47Y0TZ00'(!)           = ''              | ''                 | 'CV-47Y0TZ00'              |'L_57511_30X19-3'| 'NA'                           | 'IO'       | 'IND SMD 4.7UF +15%-25% 33A(57511)'             | 'CHIP'         | ''          | ''   | '20140820'  
 '1UH/0.95A'                    | 'SMLF'     | 'IND'    | 'CV-1010MN00'(!)           = ''              | ''                 | 'CV-1010MN00'              |'L0603'| '1UH/0.95A'                    | 'DISCRETE' | 'IND CHIP 1U 20% 0.95A(LQM18PN1R0MFRL)'         | 'CHIP'         | ''          | ''   | '20140820'  
 '1UH/0.95A'                    | 'SMLF'     | 'EMPTY'  | 'CV-1010MN00'(!)           = ''              | ''                 | 'CV-1010MN00'              |'L0603'| 'NA'                           | 'IO'       | 'IND CHIP 1U 20% 0.95A(LQM18PN1R0MFRL)'         | 'CHIP'         | ''          | ''   | '20140820'  
 '0.56UH/6.5A'                  | 'SMLF'     | 'IND'    | 'CV+5665MZ00'(!)           = ''              | ''                 | 'CV+5665MZ00'              |'L_PCMB042T'| '0.56UH/6.5A'                  | 'DISCRETE' | 'IND SMD 0.56UH +-20% 6.5A(PCMB042T-R56MS'      | 'CHIP'         | ''          | ''   | '20140820'  
 '0.56UH/6.5A'                  | 'SMLF'     | 'EMPTY'  | 'CV+5665MZ00'(!)           = ''              | ''                 | 'CV+5665MZ00'              |'L_PCMB042T'| 'NA'                           | 'IO'       | 'IND SMD 0.56UH +-20% 6.5A(PCMB042T-R56MS'      | 'CHIP'         | ''          | ''   | '20140820'  
 'HC9-6R8-R/10.3A'              | 'SMLF'     | 'IND'    | 'CV-68A3EZ00'(!)           = ''              | ''                 | 'CV-68A3EZ00'              |'L_HC9_14-1X13-1'| 'HC9-6R8-R/10.3A'              | 'DISCRETE' | 'IND SMD 6.8UF +-15% 10.3A(HC9-6R8-R)'          | 'CHIP'         | ''          | ''   | '20140820'  
 'HC9-6R8-R/10.3A'              | 'SMLF'     | 'EMPTY'  | 'CV-68A3EZ00'(!)           = ''              | ''                 | 'CV-68A3EZ00'              |'L_HC9_14-1X13-1'| 'NA'                           | 'IO'       | 'IND SMD 6.8UF +-15% 10.3A(HC9-6R8-R)'          | 'CHIP'         | ''          | ''   | '20140820'  
 '0.128UH/22.2A'                | 'SMLF'     | 'IND'    | 'CV+12M2MZ00'(!)           = 'Non-Preferred' | 'End of Life'      | 'CV+12M2MZ00'              |'L_HCM0503_5-15X5-1_EOL'| '0.128UH/22.2A'                | 'DISCRETE' | 'IND SMD 0.128U +-20% 22.2A(HCM0503-R20-R'      | 'CHIP'         | ''          | ''   | '20140820'  
 '0.128UH/22.2A'                | 'SMLF'     | 'EMPTY'  | 'CV+12M2MZ00'(!)           = 'Non-Preferred' | 'End of Life'      | 'CV+12M2MZ00'              |'L_HCM0503_5-15X5-1_EOL'| 'NA'                           | 'IO'       | 'IND SMD 0.128U +-20% 22.2A(HCM0503-R20-R'      | 'CHIP'         | ''          | ''   | '20140820'  
 '100UH/0.9A'                   | 'SMLF'     | 'IND'    | 'TV11009MZ01'(!)           = 'Potential'     | 'End of Life'      | 'TV11009MZ01'              |'L_CLF7045T_7-2X6-9_EOL'| '100UH/0.9A'                   | 'DISCRETE' | 'IND SMD 100UH 20%,0.9A(CLF7045T)EMS SEL'       | 'CHIP'         | ''          | ''   | '20140827'  
 '100UH/0.9A'                   | 'SMLF'     | 'EMPTY'  | 'TV11009MZ01'(!)           = 'Potential'     | 'End of Life'      | 'TV11009MZ01'              |'L_CLF7045T_7-2X6-9_EOL'| 'NA'                           | 'IO'       | 'IND SMD 100UH 20%,0.9A(CLF7045T)EMS SEL'       | 'CHIP'         | ''          | ''   | '20140827'  
 'BLM21PG220SN1D/6A'            | 'SMLF'     | 'IND'    | 'CX1PG220004'(!)           = 'End of Design' | 'Comp-Approve'     | 'CX1PG220004'              |'L0805'| 'BLM21PG220SN1D/6A'            | 'DISCRETE' | 'EMI FILTER CHIP BLM21PG220SN1D(22 6A)'         | 'CHIP'         | ''          | ''   | '20140827'  
 'BLM21PG220SN1D/6A'            | 'SMLF'     | 'EMPTY'  | 'CX1PG220004'(!)           = 'End of Design' | 'Comp-Approve'     | 'CX1PG220004'              |'L0805'| 'NA'                           | 'IO'       | 'EMI FILTER CHIP BLM21PG220SN1D(22 6A)'         | 'CHIP'         | ''          | ''   | '20140827'  
 '270NH/61A'                    | 'SMLF'     | 'IND'    | 'CV+27^0KZ11'(!)           = 'End of Design' | 'Comp-Approve'     | 'CV+27^0KZ11'              |'L_FP1110V1_10-7X7-5'| '270NH/61A'                    | 'DISCRETE' | 'IND SMD 270NH +-10% 61A(FP1110V1-R27-R)'       | 'CHIP'         | ''          | ''   | '20140828'  
 '270NH/61A'                    | 'SMLF'     | 'EMPTY'  | 'CV+27^0KZ11'(!)           = 'End of Design' | 'Comp-Approve'     | 'CV+27^0KZ11'              |'L_FP1110V1_10-7X7-5'| 'NA'                           | 'IO'       | 'IND SMD 270NH +-10% 61A(FP1110V1-R27-R)'       | 'CHIP'         | ''          | ''   | '20140828'  
 '220NH/61A'                    | 'SMLF'     | 'IND'    | 'CV+22^0KZ09'(!)           = ''              | ''                 | 'CV+22^0KZ09'              |'L_FP1110V1_10-7X7-5'| '220NH/61A'                    | 'DISCRETE' | 'IND SMD 220NH +-10% 61A(FP1110V1-R22-R)'       | 'CHIP'         | ''          | ''   | '20140828'  
 '220NH/61A'                    | 'SMLF'     | 'EMPTY'  | 'CV+22^0KZ09'(!)           = ''              | ''                 | 'CV+22^0KZ09'              |'L_FP1110V1_10-7X7-5'| 'NA'                           | 'IO'       | 'IND SMD 220NH +-10% 61A(FP1110V1-R22-R)'       | 'CHIP'         | ''          | ''   | '20140828'  
 '4.7UH/650MA'                  | 'SMLF'     | 'IND'    | 'CV-4707MZ16'(!)           = ''              | ''                 | 'CV-4707MZ16'              |'L1210XC_H61'| '4.7UH/650MA'                  | 'DISCRETE' | 'IND SMD 4.7UH 20% 650MA(LQH32DN4R7M53L)'       | 'CHIP'         | ''          | ''   | '20140901'  
 '4.7UH/650MA'                  | 'SMLF'     | 'EMPTY'  | 'CV-4707MZ16'(!)           = ''              | ''                 | 'CV-4707MZ16'              |'L1210XC_H61'| 'NA'                           | 'IO'       | 'IND SMD 4.7UH 20% 650MA(LQH32DN4R7M53L)'       | 'CHIP'         | ''          | ''   | '20140901'  
 '2.2UH/970MA'                  | 'SMLF'     | 'IND'    | 'CV-2210TZ00'(!)           = ''              | ''                 | 'CV-2210TZ00'              |'L1210XB'| '2.2UH/970MA'                  | 'DISCRETE' | 'IND SMD 2.2UH 30% 970MA(LQH32PB2R2NN0L)'       | 'CHIP'         | ''          | ''   | '20140901'  
 '2.2UH/970MA'                  | 'SMLF'     | 'EMPTY'  | 'CV-2210TZ00'(!)           = ''              | ''                 | 'CV-2210TZ00'              |'L1210XB'| 'NA'                           | 'IO'       | 'IND SMD 2.2UH 30% 970MA(LQH32PB2R2NN0L)'       | 'CHIP'         | ''          | ''   | '20140901'  
 '320NH/61A'                    | 'SMLF'     | 'IND'    | 'CV+32^0KZ06'(!)           = ''              | ''                 | 'CV+32^0KZ06'              |'L_FP1110V1_10-7X7-5XA'| '320NH/61A'                    | 'DISCRETE' | 'IND SMD 320NH +-10% 61A(FP1110V1-R32-R)'       | 'CHIP'         | ''          | ''   | '20140903'  
 '320NH/61A'                    | 'SMLF'     | 'EMPTY'  | 'CV+32^0KZ06'(!)           = ''              | ''                 | 'CV+32^0KZ06'              |'L_FP1110V1_10-7X7-5XA'| 'NA'                           | 'IO'       | 'IND SMD 320NH +-10% 61A(FP1110V1-R32-R)'       | 'CHIP'         | ''          | ''   | '20140903'  
 '1.0UH/8.0A'                   | 'SMLF'     | 'IND'    | 'CV-1080MZ00'(!)           = ''              | ''                 | 'CV-1080MZ00'              |'L_XFL4020_4X4'| '1.0UH/8.0A'                   | 'DISCRETE' | 'IND SMD 1.0UH +-20% 8.0A(XFL4020-102MEC)'      | 'CHIP'         | ''          | ''   | '20140923'  
 '1.0UH/8.0A'                   | 'SMLF'     | 'EMPTY'  | 'CV-1080MZ00'(!)           = ''              | ''                 | 'CV-1080MZ00'              |'L_XFL4020_4X4'| 'NA'                           | 'IO'       | 'IND SMD 1.0UH +-20% 8.0A(XFL4020-102MEC)'      | 'CHIP'         | ''          | ''   | '20140923'  
 'NBQ160808T-601Y-N/0.2A'       | 'SMLF'     | 'IND'    | 'CX08T601001'(!)           = ''              | ''                 | 'CX08T601001'              |'L0603'| 'NBQ160808T-601Y-N/0.2A'       | 'DISCRETE' | 'EMI FILTER NBQ160808T-601Y-N(600,0.2A)'        | 'CHIP'         | ''          | ''   | '20140923'  
 'NBQ160808T-601Y-N/0.2A'       | 'SMLF'     | 'EMPTY'  | 'CX08T601001'(!)           = ''              | ''                 | 'CX08T601001'              |'L0603'| 'NA'                           | 'IO'       | 'EMI FILTER NBQ160808T-601Y-N(600,0.2A)'        | 'CHIP'         | ''          | ''   | '20140923'  
 '0.45UF/25A'                   | 'SMLF'     | 'IND'    | 'CV+45Q0MZ01'(!)           = ''              | ''                 | 'CV+45Q0MZ01'              |'L_PCMB104TXB'| '0.45UF/25A'                   | 'DISCRETE' | 'IND 0.45U(25A,+-20%,PCMB104T-R45MN)'           | 'CHIP'         | ''          | ''   | '20141001'  
 '0.45UF/25A'                   | 'SMLF'     | 'EMPTY'  | 'CV+45Q0MZ01'(!)           = ''              | ''                 | 'CV+45Q0MZ01'              |'L_PCMB104TXB'| 'NA'                           | 'IO'       | 'IND 0.45U(25A,+-20%,PCMB104T-R45MN)'           | 'CHIP'         | ''          | ''   | '20141001'  
 '2.2UH/0.95A'                  | 'SMLF'     | 'IND'    | 'CV-2210MN00'(!)           = ''              | 'End of Life'      | 'CV-2210MN00'              |'L0805_EOL'| '2.2UH/0.95A'                  | 'DISCRETE' | 'IND CHIP 2.2UH 20% 0.95A(CIG21L2R2MNE)'        | 'CHIP'         | ''          | ''   | '20141016'  
 '2.2UH/0.95A'                  | 'SMLF'     | 'EMPTY'  | 'CV-2210MN00'(!)           = ''              | 'End of Life'      | 'CV-2210MN00'              |'L0805_EOL'| 'NA'                           | 'IO'       | 'IND CHIP 2.2UH 20% 0.95A(CIG21L2R2MNE)'        | 'CHIP'         | ''          | ''   | '20141016'  
 '22NH/1.85MA'                  | 'SMLF'     | 'IND'    | 'CVA2219KN00'(!)           = 'End of Design' | 'End of Life'      | 'CVA2219KN00'              |'L0805_EOL'| '22NH/1.85MA'                  | 'DISCRETE' | 'IND CHIP 22NH 10% 1.85MA(MLH2012F22NKT)'       | 'CHIP'         | ''          | ''   | '20141016'  
 '22NH/1.85MA'                  | 'SMLF'     | 'EMPTY'  | 'CVA2219KN00'(!)           = 'End of Design' | 'End of Life'      | 'CVA2219KN00'              |'L0805_EOL'| 'NA'                           | 'IO'       | 'IND CHIP 22NH 10% 1.85MA(MLH2012F22NKT)'       | 'CHIP'         | ''          | ''   | '20141016'  
 '200NH/75A'                    | 'SMLF'     | 'IND'    | 'CV+20^0KZ01'(!)           = ''              | ''                 | 'CV+20^0KZ01'              |'L_HCUV117513_10-7X7-5'| '200NH/75A'                    | 'DISCRETE' | 'IND SMD 200NH +-10% 75A (HCUV117513-201)'      | 'CHIP'         | ''          | ''   | '20141022'  
 '200NH/75A'                    | 'SMLF'     | 'EMPTY'  | 'CV+20^0KZ01'(!)           = ''              | ''                 | 'CV+20^0KZ01'              |'L_HCUV117513_10-7X7-5'| 'NA'                           | 'IO'       | 'IND SMD 200NH +-10% 75A (HCUV117513-201)'      | 'CHIP'         | ''          | ''   | '20141022'  
 '160NH/98A'                    | 'SMLF'     | 'IND'    | 'CV+1698KZ00'(!)           = ''              | ''                 | 'CV+1698KZ00'              |'L_HCUVE117695_10-7X7-6'| '160NH/98A'                    | 'DISCRETE' | 'IND SMD 160NH +-10% 98A(HCUVE117695-161)'      | 'CHIP'         | ''          | ''   | '20141114'  
 '160NH/98A'                    | 'SMLF'     | 'EMPTY'  | 'CV+1698KZ00'(!)           = ''              | ''                 | 'CV+1698KZ00'              |'L_HCUVE117695_10-7X7-6'| 'NA'                           | 'IO'       | 'IND SMD 160NH +-10% 98A(HCUVE117695-161)'      | 'CHIP'         | ''          | ''   | '20141114'  
 '0.6UH/32.5A'                  | 'SMLF'     | 'IND'    | 'CV+6033KZ00'(!)           = ''              | ''                 | 'CV+6033KZ00'              |'L_HCUVD8095_8X8'| '0.6UH/32.5A'                  | 'DISCRETE' | 'IND SMD 0.6UH +-10% 32.5A(HCUVD8095-601)'      | 'CHIP'         | ''          | ''   | '201411'    
 '0.6UH/32.5A'                  | 'SMLF'     | 'EMPTY'  | 'CV+6033KZ00'(!)           = ''              | ''                 | 'CV+6033KZ00'              |'L_HCUVD8095_8X8'| 'NA'                           | 'IO'       | 'IND SMD 0.6UH +-10% 32.5A(HCUVD8095-601)'      | 'CHIP'         | ''          | ''   | '201411'    
 '0.1UH/17A'                    | 'SMLF'     | 'IND'    | 'CV+10H0MZ00'(!)           = ''              | ''                 | 'CV+10H0MZ00'              |'L_HCB444-101IN'| '0.1UH/17A'                    | 'DISCRETE' | 'IND SMD 0.1UH 20% 17A HCB444-101IN'            | 'CHIP'         | ''          | ''   | '20141201'  
 '0.1UH/17A'                    | 'SMLF'     | 'EMPTY'  | 'CV+10H0MZ00'(!)           = ''              | ''                 | 'CV+10H0MZ00'              |'L_HCB444-101IN'| 'NA'                           | 'IO'       | 'IND SMD 0.1UH 20% 17A HCB444-101IN'            | 'CHIP'         | ''          | ''   | '20141201'  
 '0.15UH/57A'                   | 'SMLF'     | 'IND'    | 'CV+15^0EZ02'(!)           = ''              | ''                 | 'CV+15^0EZ02'              |'L_HCB117555-151IN'| '0.15UH/57A'                   | 'DISCRETE' | 'IND SMD 0.15UH 15% 57A HCB117555-151IN'        | 'CHIP'         | ''          | ''   | '20141201'  
 '0.15UH/57A'                   | 'SMLF'     | 'EMPTY'  | 'CV+15^0EZ02'(!)           = ''              | ''                 | 'CV+15^0EZ02'              |'L_HCB117555-151IN'| 'NA'                           | 'IO'       | 'IND SMD 0.15UH 15% 57A HCB117555-151IN'        | 'CHIP'         | ''          | ''   | '20141201'  
 '3.3UH/13.5A'                  | 'SMLF'     | 'IND'    | 'CV-33D5MZ06'(!)           = ''              | ''                 | 'CV-33D5MZ06'              |'L_MPT730'| '3.3UH/13.5A'                  | 'DISCRETE' | 'IND SMD 3.3UH 20% 13.5A MPT730-3R3M1IN'        | 'CHIP'         | ''          | ''   | '20141201'  
 '3.3UH/13.5A'                  | 'SMLF'     | 'EMPTY'  | 'CV-33D5MZ06'(!)           = ''              | ''                 | 'CV-33D5MZ06'              |'L_MPT730'| 'NA'                           | 'IO'       | 'IND SMD 3.3UH 20% 13.5A MPT730-3R3M1IN'        | 'CHIP'         | ''          | ''   | '20141201'  
 '0.08UH/22A'                   | 'SMLF'     | 'IND'    | 'CVA80M0MZ00'(!)           = ''              | ''                 | 'CVA80M0MZ00'              |'L_HCB444-101IN'| '0.08UH/22A'                   | 'DISCRETE' | 'IND SMD 0.08UH 20% 22A HCB444-800IN'           | 'CHIP'         | ''          | ''   | '20141201'  
 '0.08UH/22A'                   | 'SMLF'     | 'EMPTY'  | 'CVA80M0MZ00'(!)           = ''              | ''                 | 'CVA80M0MZ00'              |'L_HCB444-101IN'| 'NA'                           | 'IO'       | 'IND SMD 0.08UH 20% 22A HCB444-800IN'           | 'CHIP'         | ''          | ''   | '20141201'  
 '270NH/64A'                    | 'SMLF'     | 'IND'    | 'CV+27^0KZ12'(!)           = ''              | ''                 | 'CV+27^0KZ12'              |'L_HCUV117512_10-7X7-5'| '270NH/64A'                    | 'DISCRETE' | 'IND SMD 270NH +-10% 64A(HCUV117512-271)'       | 'CHIP'         | ''          | ''   | '20141208'  
 '270NH/64A'                    | 'SMLF'     | 'EMPTY'  | 'CV+27^0KZ12'(!)           = ''              | ''                 | 'CV+27^0KZ12'              |'L_HCUV117512_10-7X7-5'| 'NA'                           | 'IO'       | 'IND SMD 270NH +-10% 64A(HCUV117512-271)'       | 'CHIP'         | ''          | ''   | '20141208'  
 '320NH/54A'                    | 'SMLF'     | 'IND'    | 'CV+32^0KZ08'(!)           = ''              | ''                 | 'CV+32^0KZ08'              |'L_HCUV117512_10-7X7-5'| '320NH/54A'                    | 'DISCRETE' | 'IND SMD 320NH +-10% 54A(HCUV117512-321)'       | 'CHIP'         | ''          | ''   | '20141208'  
 '320NH/54A'                    | 'SMLF'     | 'EMPTY'  | 'CV+32^0KZ08'(!)           = ''              | ''                 | 'CV+32^0KZ08'              |'L_HCUV117512_10-7X7-5'| 'NA'                           | 'IO'       | 'IND SMD 320NH +-10% 54A(HCUV117512-321)'       | 'CHIP'         | ''          | ''   | '20141208'  
 '400NH/43.5A'                  | 'SMLF'     | 'IND'    | 'CV+40^0KZ00'(!)           = ''              | ''                 | 'CV+40^0KZ00'              |'L_HCUV117512_10-7X7-5'| '400NH/43.5A'                  | 'DISCRETE' | 'IND SMD 400NH +-10% 43.5A(HCUV117512-401'      | 'CHIP'         | ''          | ''   | '20141208'  
 '400NH/43.5A'                  | 'SMLF'     | 'EMPTY'  | 'CV+40^0KZ00'(!)           = ''              | ''                 | 'CV+40^0KZ00'              |'L_HCUV117512_10-7X7-5'| 'NA'                           | 'IO'       | 'IND SMD 400NH +-10% 43.5A(HCUV117512-401'      | 'CHIP'         | ''          | ''   | '20141208'  
 '600NH/26A'                    | 'SMLF'     | 'IND'    | 'CV+60^0KZ00'(!)           = ''              | ''                 | 'CV+60^0KZ00'              |'L_HCUV117512_10-7X7-5'| '600NH/26A'                    | 'DISCRETE' | 'IND SMD 600NH +-10% 26A(HCUV117512-601)'       | 'CHIP'         | ''          | ''   | '20141208'  
 '600NH/26A'                    | 'SMLF'     | 'EMPTY'  | 'CV+60^0KZ00'(!)           = ''              | ''                 | 'CV+60^0KZ00'              |'L_HCUV117512_10-7X7-5'| 'NA'                           | 'IO'       | 'IND SMD 600NH +-10% 26A(HCUV117512-601)'       | 'CHIP'         | ''          | ''   | '20141208'  
 '220NH/81A'                    | 'SMLF'     | 'IND'    | 'CV+22^0KZ10'(!)           = ''              | ''                 | 'CV+22^0KZ10'              |'L_HCUV117512_10-7X7-5'| '220NH/81A'                    | 'DISCRETE' | 'IND SMD 220NH +-10% 81A(HCUV117512-221)'       | 'CHIP'         | ''          | ''   | '20141209'  
 '220NH/81A'                    | 'SMLF'     | 'EMPTY'  | 'CV+22^0KZ10'(!)           = ''              | ''                 | 'CV+22^0KZ10'              |'L_HCUV117512_10-7X7-5'| 'NA'                           | 'IO'       | 'IND SMD 220NH +-10% 81A(HCUV117512-221)'       | 'CHIP'         | ''          | ''   | '20141209'  
 '250NH/70A'                    | 'SMLF'     | 'IND'    | 'CV+25^0KZ02'(!)           = ''              | ''                 | 'CV+25^0KZ02'              |'L_HCUV117512_10-7X7-5'| '250NH/70A'                    | 'DISCRETE' | 'IND SMD 250NH +-10% 70A(HCUV117512-251)'       | 'CHIP'         | ''          | ''   | '20141209'  
 '250NH/70A'                    | 'SMLF'     | 'EMPTY'  | 'CV+25^0KZ02'(!)           = ''              | ''                 | 'CV+25^0KZ02'              |'L_HCUV117512_10-7X7-5'| 'NA'                           | 'IO'       | 'IND SMD 250NH +-10% 70A(HCUV117512-251)'       | 'CHIP'         | ''          | ''   | '20141209'  
 '470NH/36A'                    | 'SMLF'     | 'IND'    | 'CV+47^0KZ05'(!)           = ''              | ''                 | 'CV+47^0KZ05'              |'L_HCUV117512_10-7X7-5'| '470NH/36A'                    | 'DISCRETE' | 'IND SMD 470NH +-10% 36A(HCUV117512-471)'       | 'CHIP'         | ''          | ''   | '20141209'  
 '470NH/36A'                    | 'SMLF'     | 'EMPTY'  | 'CV+47^0KZ05'(!)           = ''              | ''                 | 'CV+47^0KZ05'              |'L_HCUV117512_10-7X7-5'| 'NA'                           | 'IO'       | 'IND SMD 470NH +-10% 36A(HCUV117512-471)'       | 'CHIP'         | ''          | ''   | '20141209'  
 '2.2UH/3A'                     | 'SMLF'     | 'IND'    | 'CV-2230MZ09'(!)           = ''              | ''                 | 'CV-2230MZ09'              |'L_IHLP1616AB_4-45X4-06'| '2.2UH/3A'                     | 'DISCRETE' | 'IND SMD 2.2UH +-20% 3A(IHLP1616ABER2R2M)'      | 'CHIP'         | ''          | ''   | '20141215'  
 '2.2UH/3A'                     | 'SMLF'     | 'EMPTY'  | 'CV-2230MZ09'(!)           = ''              | ''                 | 'CV-2230MZ09'              |'L_IHLP1616AB_4-45X4-06'| 'NA'                           | 'IO'       | 'IND SMD 2.2UH +-20% 3A(IHLP1616ABER2R2M)'      | 'CHIP'         | ''          | ''   | '20141215'  
 '2.2UH/12A'                    | 'SMLF'     | 'IND'    | 'CV-22C0MZ10'(!)           = ''              | ''                 | 'CV-22C0MZ10'              |'L_PCMB104TXB'| '2.2UH/12A'                    | 'DISCRETE' | 'IND SMD 2.2UH +-20% 12A(PIMC104T-2R2MN)'       | 'CHIP'         | ''          | ''   | '20141225'  
 '2.2UH/12A'                    | 'SMLF'     | 'EMPTY'  | 'CV-22C0MZ10'(!)           = ''              | ''                 | 'CV-22C0MZ10'              |'L_PCMB104TXB'| 'NA'                           | 'IO'       | 'IND SMD 2.2UH +-20% 12A(PIMC104T-2R2MN)'       | 'CHIP'         | ''          | ''   | '20141225'  
 'NBQ160808T-300Y-N/0.5A'       | 'SMLF'     | 'IND'    | 'CX08T300002'(!)           = ''              | ''                 | 'CX08T300002'              |'L0603'| 'NBQ160808T-300Y-N/0.5A'       | 'DISCRETE' | 'EMI FILTER NBQ160808T-300Y-N(30,0.5A)'         | 'CHIP'         | ''          | ''   | '20150303'  
 'NBQ160808T-300Y-N/0.5A'       | 'SMLF'     | 'EMPTY'  | 'CX08T300002'(!)           = ''              | ''                 | 'CX08T300002'              |'L0603'| 'NA'                           | 'IO'       | 'EMI FILTER NBQ160808T-300Y-N(30,0.5A)'         | 'CHIP'         | ''          | ''   | '20150303'  
 'BLM15AG100SN1D/1A'            | 'SMLF'     | 'IND'    | 'CX5AG100001'(!)           = ''              | ''                 | 'CX5AG100001'              |'L0402'| 'BLM15AG100SN1D/1A'            | 'DISCRETE' | 'EMI FILTER CHIP BLM15AG100SN1D(10,1A)'         | 'CHIP'         | ''          | ''   | '20150310'  
 'BLM15AG100SN1D/1A'            | 'SMLF'     | 'EMPTY'  | 'CX5AG100001'(!)           = ''              | ''                 | 'CX5AG100001'              |'L0402'| 'NA'                           | 'IO'       | 'EMI FILTER CHIP BLM15AG100SN1D(10,1A)'         | 'CHIP'         | ''          | ''   | '20150310'  
 '100UH/1.9A'                   | 'SMLF'     | 'IND'    | 'CV11019MZ00'(!)           = ''              | ''                 | 'CV11019MZ00'              |'L_MSCDRI-127F'| '100UH/1.9A'                   | 'DISCRETE' | 'IND SMD 100UH 20% 1.9A MSCDRI-127F-101M'       | 'CHIP'         | ''          | ''   | '20150331'  
 '100UH/1.9A'                   | 'SMLF'     | 'EMPTY'  | 'CV11019MZ00'(!)           = ''              | ''                 | 'CV11019MZ00'              |'L_MSCDRI-127F'| 'NA'                           | 'IO'       | 'IND SMD 100UH 20% 1.9A MSCDRI-127F-101M'       | 'CHIP'         | ''          | ''   | '20150331'  
 '120ohm/3A'                    | 'SMLF'     | 'IND'    | 'CX8SG121000'(!)           = 'End of Design' | 'Comp-Approve'     | 'CX8SG121000'              |'L0603'| '120ohm/3A'                    | 'DISCRETE' | 'EMI FILTER BEAD BLM18SG121TN1D(120.3A)'        | 'CHIP'         | ''          | ''   | '20150415'  
 '120ohm/3A'                    | 'SMLF'     | 'EMPTY'  | 'CX8SG121000'(!)           = 'End of Design' | 'Comp-Approve'     | 'CX8SG121000'              |'L0603'| 'NA'                           | 'IO'       | 'EMI FILTER BEAD BLM18SG121TN1D(120.3A)'        | 'CHIP'         | ''          | ''   | '20150415'  
 '0.15UH/35A'                   | 'SMLF'     | 'IND'    | 'CV+15^0KZ04'(!)           = ''              | ''                 | 'CV+15^0KZ04'              |'L_HCUVE575775_5-7X5-7'| '0.15UH/35A'                   | 'DISCRETE' | 'IND SMD 0.15UH 10% 35A(HCUVE575775-151)'       | 'CHIP'         | ''          | ''   | '20150415'  
 '0.15UH/35A'                   | 'SMLF'     | 'EMPTY'  | 'CV+15^0KZ04'(!)           = ''              | ''                 | 'CV+15^0KZ04'              |'L_HCUVE575775_5-7X5-7'| 'NA'                           | 'IO'       | 'IND SMD 0.15UH 10% 35A(HCUVE575775-151)'       | 'CHIP'         | ''          | ''   | '20150415'  
 'BLM18SG260TN1D/6A'            | 'SMLF'     | 'IND'    | 'CX8SG260000'(!)           = 'End of Design' | 'Comp-Approve'     | 'CX8SG260000'              |'L0603'| 'BLM18SG260TN1D/6A'            | 'DISCRETE' | 'EMI FILTER BLM18SG260TN1D(26,6A)'              | 'CHIP'         | ''          | ''   | '20150416'  
 'BLM18SG260TN1D/6A'            | 'SMLF'     | 'EMPTY'  | 'CX8SG260000'(!)           = 'End of Design' | 'Comp-Approve'     | 'CX8SG260000'              |'L0603'| 'NA'                           | 'IO'       | 'EMI FILTER BLM18SG260TN1D(26,6A)'              | 'CHIP'         | ''          | ''   | '20150416'  
 '1.5UH/16A'                    | 'SMLF'     | 'IND'    | 'CV-15G0MZ00'(!)           = ''              | ''                 | 'CV-15G0MZ00'              |'L_MMD-10DZ-1R5M-X1Q'| '1.5UH/16A'                    | 'DISCRETE' | 'IND SMD 1.5UH+-20%16A(MMD-10DZ-1R5M-X1Q)'      | 'CHIP'         | ''          | ''   | '20150429'  
 '1.5UH/16A'                    | 'SMLF'     | 'EMPTY'  | 'CV-15G0MZ00'(!)           = ''              | ''                 | 'CV-15G0MZ00'              |'L_MMD-10DZ-1R5M-X1Q'| 'NA'                           | 'IO'       | 'IND SMD 1.5UH+-20%16A(MMD-10DZ-1R5M-X1Q)'      | 'CHIP'         | ''          | ''   | '20150429'  
 '180NH/85A'                    | 'SMLF'     | 'IND'    | 'CV+18^0KZ04'(!)           = ''              | ''                 | 'CV+18^0KZ04'              |'L_HCUV106411-401G'| '180NH/85A'                    | 'DISCRETE' | 'IND SMD 180NH +-10% 85A(HCUV106411-181)'       | 'CHIP'         | ''          | ''   | '20150528'  
 '180NH/85A'                    | 'SMLF'     | 'EMPTY'  | 'CV+18^0KZ04'(!)           = ''              | ''                 | 'CV+18^0KZ04'              |'L_HCUV106411-401G'| 'NA'                           | 'IO'       | 'IND SMD 180NH +-10% 85A(HCUV106411-181)'       | 'CHIP'         | ''          | ''   | '20150528'  
 '200NH/76A'                    | 'SMLF'     | 'IND'    | 'CV+20^0KZ02'(!)           = ''              | ''                 | 'CV+20^0KZ02'              |'L_HCUV106411-401G'| '200NH/76A'                    | 'DISCRETE' | 'IND SMD 200NH +-10% 76A(HCUV106411-201)'       | 'CHIP'         | ''          | ''   | '20150528'  
 '200NH/76A'                    | 'SMLF'     | 'EMPTY'  | 'CV+20^0KZ02'(!)           = ''              | ''                 | 'CV+20^0KZ02'              |'L_HCUV106411-401G'| 'NA'                           | 'IO'       | 'IND SMD 200NH +-10% 76A(HCUV106411-201)'       | 'CHIP'         | ''          | ''   | '20150528'  
 '220NH/69A'                    | 'SMLF'     | 'IND'    | 'CV+22^0KZ14'(!)           = ''              | ''                 | 'CV+22^0KZ14'              |'L_HCUV106411-401G'| '220NH/69A'                    | 'DISCRETE' | 'IND SMD 220NH +-10% 69A(HCUV106411-221)'       | 'CHIP'         | ''          | ''   | '20150528'  
 '220NH/69A'                    | 'SMLF'     | 'EMPTY'  | 'CV+22^0KZ14'(!)           = ''              | ''                 | 'CV+22^0KZ14'              |'L_HCUV106411-401G'| 'NA'                           | 'IO'       | 'IND SMD 220NH +-10% 69A(HCUV106411-221)'       | 'CHIP'         | ''          | ''   | '20150528'  
 '220NH/75A'                    | 'SMLF'     | 'IND'    | 'CV+22^0KZ16'(!)           = 'End of Design' | 'Comp-Approve'     | 'CV+22^0KZ16'              |'L_HCUVE117512D'| '220NH/75A'                    | 'DISCRETE' | 'IND SMD 220NH 10% 75A(HCUVE117512D-221)'       | 'CHIP'         | ''          | ''   | '20150702'  
 '220NH/75A'                    | 'SMLF'     | 'EMPTY'  | 'CV+22^0KZ16'(!)           = 'End of Design' | 'Comp-Approve'     | 'CV+22^0KZ16'              |'L_HCUVE117512D'| 'NA'                           | 'IO'       | 'IND SMD 220NH 10% 75A(HCUVE117512D-221)'       | 'CHIP'         | ''          | ''   | '20150702'  
 '250NH/66A'                    | 'SMLF'     | 'IND'    | 'CV+25^0KZ03'(!)           = 'End of Design' | 'Comp-Approve'     | 'CV+25^0KZ03'              |'L_HCUVE117512D'| '250NH/66A'                    | 'DISCRETE' | 'IND SMD 250NH 10% 66A(HCUVE117512D-251)'       | 'CHIP'         | ''          | ''   | '20150702'  
 '250NH/66A'                    | 'SMLF'     | 'EMPTY'  | 'CV+25^0KZ03'(!)           = 'End of Design' | 'Comp-Approve'     | 'CV+25^0KZ03'              |'L_HCUVE117512D'| 'NA'                           | 'IO'       | 'IND SMD 250NH 10% 66A(HCUVE117512D-251)'       | 'CHIP'         | ''          | ''   | '20150702'  
 '270NH/60A'                    | 'SMLF'     | 'IND'    | 'CV+27^0KZ13'(!)           = 'End of Design' | 'Comp-Approve'     | 'CV+27^0KZ13'              |'L_HCUVE117512D'| '270NH/60A'                    | 'DISCRETE' | 'IND SMD 270NH 10% 60A(HCUVE117512D-271)'       | 'CHIP'         | ''          | ''   | '20150702'  
 '270NH/60A'                    | 'SMLF'     | 'EMPTY'  | 'CV+27^0KZ13'(!)           = 'End of Design' | 'Comp-Approve'     | 'CV+27^0KZ13'              |'L_HCUVE117512D'| 'NA'                           | 'IO'       | 'IND SMD 270NH 10% 60A(HCUVE117512D-271)'       | 'CHIP'         | ''          | ''   | '20150702'  
 '320NH/51A'                    | 'SMLF'     | 'IND'    | 'CV+32^0KZ09'(!)           = 'End of Design' | 'Comp-Approve'     | 'CV+32^0KZ09'              |'L_HCUVE117512D'| '320NH/51A'                    | 'DISCRETE' | 'IND SMD 320NH 10% 51A(HCUVE117512D-321)'       | 'CHIP'         | ''          | ''   | '20150702'  
 '320NH/51A'                    | 'SMLF'     | 'EMPTY'  | 'CV+32^0KZ09'(!)           = 'End of Design' | 'Comp-Approve'     | 'CV+32^0KZ09'              |'L_HCUVE117512D'| 'NA'                           | 'IO'       | 'IND SMD 320NH 10% 51A(HCUVE117512D-321)'       | 'CHIP'         | ''          | ''   | '20150702'  
 '400NH/41A'                    | 'SMLF'     | 'IND'    | 'CV+40^0KZ01'(!)           = 'End of Design' | 'Comp-Approve'     | 'CV+40^0KZ01'              |'L_HCUVE117512D'| '400NH/41A'                    | 'DISCRETE' | 'IND SMD 400NH 10% 41A(HCUVE117512D-401)'       | 'CHIP'         | ''          | ''   | '20150702'  
 '400NH/41A'                    | 'SMLF'     | 'EMPTY'  | 'CV+40^0KZ01'(!)           = 'End of Design' | 'Comp-Approve'     | 'CV+40^0KZ01'              |'L_HCUVE117512D'| 'NA'                           | 'IO'       | 'IND SMD 400NH 10% 41A(HCUVE117512D-401)'       | 'CHIP'         | ''          | ''   | '20150702'  
 '470NH/34A'                    | 'SMLF'     | 'IND'    | 'CV+47Z0KZ00'(!)           = 'End of Design' | 'Comp-Approve'     | 'CV+47Z0KZ00'              |'L_HCUVE117512D'| '470NH/34A'                    | 'DISCRETE' | 'IND SMD 470NH 10% 34A(HCUVE117512D-471)'       | 'CHIP'         | ''          | ''   | '20150702'  
 '470NH/34A'                    | 'SMLF'     | 'EMPTY'  | 'CV+47Z0KZ00'(!)           = 'End of Design' | 'Comp-Approve'     | 'CV+47Z0KZ00'              |'L_HCUVE117512D'| 'NA'                           | 'IO'       | 'IND SMD 470NH 10% 34A(HCUVE117512D-471)'       | 'CHIP'         | ''          | ''   | '20150702'  
 '600NH/24.5A'                  | 'SMLF'     | 'IND'    | 'CV+60Q0KZ00'(!)           = ''              | ''                 | 'CV+60Q0KZ00'              |'L_HCUVE117512D'| '600NH/24.5A'                  | 'DISCRETE' | 'IND SMD 600N 10% 24.5A(HCUVE117512D-601)'      | 'CHIP'         | ''          | ''   | '20150702'  
 '600NH/24.5A'                  | 'SMLF'     | 'EMPTY'  | 'CV+60Q0KZ00'(!)           = ''              | ''                 | 'CV+60Q0KZ00'              |'L_HCUVE117512D'| 'NA'                           | 'IO'       | 'IND SMD 600N 10% 24.5A(HCUVE117512D-601)'      | 'CHIP'         | ''          | ''   | '20150702'  
 '100NH/42A'                    | 'SMLF'     | 'IND'    | 'CV+10^0MZ10'(!)           = ''              | ''                 | 'CV+10^0MZ10'              |'L_HCUVE756257_7X5-7'| '100NH/42A'                    | 'DISCRETE' | 'IND SMD 100NH 20% 42A(HCUVE756257-101)'        | 'CHIP'         | ''          | ''   | '20150703'  
 '100NH/42A'                    | 'SMLF'     | 'EMPTY'  | 'CV+10^0MZ10'(!)           = ''              | ''                 | 'CV+10^0MZ10'              |'L_HCUVE756257_7X5-7'| 'NA'                           | 'IO'       | 'IND SMD 100NH 20% 42A(HCUVE756257-101)'        | 'CHIP'         | ''          | ''   | '20150703'  
 '0.22UH/15A'                   | 'SMLF'     | 'IND'    | 'CV+22F0MZ00'(!)           = ''              | ''                 | 'CV+22F0MZ00'              |'L_CMLS041B_4-4X4-2'| '0.22UH/15A'                   | 'DISCRETE' | 'IND SMD 0.22UH +-20% 15A(CMLS041B-R22MS)'      | 'CHIP'         | ''          | ''   | '20150707'  
 '0.22UH/15A'                   | 'SMLF'     | 'EMPTY'  | 'CV+22F0MZ00'(!)           = ''              | ''                 | 'CV+22F0MZ00'              |'L_CMLS041B_4-4X4-2'| 'NA'                           | 'IO'       | 'IND SMD 0.22UH +-20% 15A(CMLS041B-R22MS)'      | 'CHIP'         | ''          | ''   | '20150707'  
 '0.36UH/24A'                   | 'SMLF'     | 'IND'    | 'CV+36P0MZ01'(!)           = ''              | ''                 | 'CV+36P0MZ01'              |'L_PCME064T-R36MS1R407'| '0.36UH/24A'                   | 'DISCRETE' | 'IND SMD 0.36UH20%24A PCME064T-R36MS1R407'      | 'CHIP'         | ''          | ''   | '20150708'  
 '0.36UH/24A'                   | 'SMLF'     | 'EMPTY'  | 'CV+36P0MZ01'(!)           = ''              | ''                 | 'CV+36P0MZ01'              |'L_PCME064T-R36MS1R407'| 'NA'                           | 'IO'       | 'IND SMD 0.36UH20%24A PCME064T-R36MS1R407'      | 'CHIP'         | ''          | ''   | '20150708'  
 '0.22UH/13A'                   | 'SMLF'     | 'IND'    | 'CV+22D0MZ00'(!)           = ''              | ''                 | 'CV+22D0MZ00'              |'L_MMD-04BZ-1R5M-X2'| '0.22UH/13A'                   | 'DISCRETE' | 'IND SMD 0.22UH20%13A(MMD-04BZ-R22M-V1Q)'       | 'CHIP'         | ''          | ''   | '20150713'  
 '0.22UH/13A'                   | 'SMLF'     | 'EMPTY'  | 'CV+22D0MZ00'(!)           = ''              | ''                 | 'CV+22D0MZ00'              |'L_MMD-04BZ-1R5M-X2'| 'NA'                           | 'IO'       | 'IND SMD 0.22UH20%13A(MMD-04BZ-R22M-V1Q)'       | 'CHIP'         | ''          | ''   | '20150713'  
 '5.6NH/760MA'                  | 'SMLF'     | 'IND'    | 'CVB5608JZ00'(!)           = ''              | ''                 | 'CVB5608JZ00'              |'L0402CS'| '5.6NH/760MA'                  | 'DISCRETE' | 'IND SMD 5.6N 5% 760MA(CS0402-5N6J-S)'          | 'CHIP'         | ''          | ''   | '20150713'  
 '5.6NH/760MA'                  | 'SMLF'     | 'EMPTY'  | 'CVB5608JZ00'(!)           = ''              | ''                 | 'CVB5608JZ00'              |'L0402CS'| 'NA'                           | 'IO'       | 'IND SMD 5.6N 5% 760MA(CS0402-5N6J-S)'          | 'CHIP'         | ''          | ''   | '20150713'  
 '100NH/16A'                    | 'SMLF'     | 'IND'    | 'CV+10G0MZ04'(!)           = ''              | ''                 | 'CV+10G0MZ04'              |'L_HCBS4545_4-5X4-5'| '100NH/16A'                    | 'DISCRETE' | 'IND SMD 100NH 20% 16A(HCBS4545-101)'           | 'CHIP'         | ''          | ''   | '20150715'  
 '100NH/16A'                    | 'SMLF'     | 'EMPTY'  | 'CV+10G0MZ04'(!)           = ''              | ''                 | 'CV+10G0MZ04'              |'L_HCBS4545_4-5X4-5'| 'NA'                           | 'IO'       | 'IND SMD 100NH 20% 16A(HCBS4545-101)'           | 'CHIP'         | ''          | ''   | '20150715'  
 '70NH/60A'                     | 'SMLF'     | 'IND'    | 'CVA70^0MZ00'(!)           = 'End of Design' | 'Comp-Approve'     | 'CVA70^0MZ00'              |'L_HCBS6170_6-1X6'| '70NH/60A'                     | 'DISCRETE' | 'IND SMD 70NH 20% 60A(HCBS6170-700)'            | 'CHIP'         | ''          | ''   | '20150715'  
 '70NH/60A'                     | 'SMLF'     | 'EMPTY'  | 'CVA70^0MZ00'(!)           = 'End of Design' | 'Comp-Approve'     | 'CVA70^0MZ00'              |'L_HCBS6170_6-1X6'| 'NA'                           | 'IO'       | 'IND SMD 70NH 20% 60A(HCBS6170-700)'            | 'CHIP'         | ''          | ''   | '20150715'  
 '0.22UH/13A'                   | 'SMLF'     | 'IND'    | 'CV+22D0MZ02'(!)           = ''              | ''                 | 'CV+22D0MZ02'              |'L_CMMS042T_4-4X4-2'| '0.22UH/13A'                   | 'DISCRETE' | 'IND SMD 0.22UH 20% 13A(CMMS042T-R22MS)'        | 'CHIP'         | ''          | ''   | '20150724'  
 '0.22UH/13A'                   | 'SMLF'     | 'EMPTY'  | 'CV+22D0MZ02'(!)           = ''              | ''                 | 'CV+22D0MZ02'              |'L_CMMS042T_4-4X4-2'| 'NA'                           | 'IO'       | 'IND SMD 0.22UH 20% 13A(CMMS042T-R22MS)'        | 'CHIP'         | ''          | ''   | '20150724'  
 '0.24UH/4.8A'                  | 'SMLF'     | 'IND'    | 'CV+2448TZ00'(!)           = ''              | 'End of Life'      | 'CV+2448TZ00'              |'L_MLV-TP10NR24N-XP_2X1-6_EOL'| '0.24UH/4.8A'                  | 'DISCRETE' | 'IND SMD 0.24UH 30% 4.8A(MLV-TP10NR24N-XP'      | 'CHIP'         | ''          | ''   | '20150729'  
 '0.24UH/4.8A'                  | 'SMLF'     | 'EMPTY'  | 'CV+2448TZ00'(!)           = ''              | 'End of Life'      | 'CV+2448TZ00'              |'L_MLV-TP10NR24N-XP_2X1-6_EOL'| 'NA'                           | 'IO'       | 'IND SMD 0.24UH 30% 4.8A(MLV-TP10NR24N-XP'      | 'CHIP'         | ''          | ''   | '20150729'  
 '0.36UH/24A'                   | 'SMLF'     | 'IND'    | 'CV+36P0MZ02'(!)           = ''              | ''                 | 'CV+36P0MZ02'              |'L_MMD-06DZ'| '0.36UH/24A'                   | 'DISCRETE' | 'IND SMD 0.36UH 20% 24A(MMD-06DZER36MGX5Q'      | 'CHIP'         | ''          | ''   | '20150730'  
 '0.36UH/24A'                   | 'SMLF'     | 'EMPTY'  | 'CV+36P0MZ02'(!)           = ''              | ''                 | 'CV+36P0MZ02'              |'L_MMD-06DZ'| 'NA'                           | 'IO'       | 'IND SMD 0.36UH 20% 24A(MMD-06DZER36MGX5Q'      | 'CHIP'         | ''          | ''   | '20150730'  
 '68NH/0.3A'                    | 'SMLF'     | 'IND'    | 'CVA6803MZ00'(!)           = ''              | ''                 | 'CVA6803MZ00'              |'L0805'| '68NH/0.3A'                    | 'DISCRETE' | 'IND SMD 68NH 20% 0.3A(MLF2012D68NMT)'          | 'CHIP'         | ''          | ''   | '20150814'  
 '68NH/0.3A'                    | 'SMLF'     | 'EMPTY'  | 'CVA6803MZ00'(!)           = ''              | ''                 | 'CVA6803MZ00'              |'L0805'| 'NA'                           | 'IO'       | 'IND SMD 68NH 20% 0.3A(MLF2012D68NMT)'          | 'CHIP'         | ''          | ''   | '20150814'  
 '0.56UH/18A'                   | 'SMLF'     | 'IND'    | 'CV+56I0MZ02'(!)           = ''              | ''                 | 'CV+56I0MZ02'              |'L_PCMB065T'| '0.56UH/18A'                   | 'DISCRETE' | 'IND SMD 0.56UH +-20% 18A(PIMB065T-R56MS)'      | 'CHIP'         | ''          | ''   | '20150907'  
 '0.56UH/18A'                   | 'SMLF'     | 'EMPTY'  | 'CV+56I0MZ02'(!)           = ''              | ''                 | 'CV+56I0MZ02'              |'L_PCMB065T'| 'NA'                           | 'IO'       | 'IND SMD 0.56UH +-20% 18A(PIMB065T-R56MS)'      | 'CHIP'         | ''          | ''   | '20150907'  
 '47NH/0.3A'                    | 'SMLF'     | 'IND'    | 'CVA4703JN03'(!)           = ''              | ''                 | 'CVA4703JN03'              |'L0603'| '47NH/0.3A'                    | 'DISCRETE' | 'IND SMD 47NH 5% 0.3A(LQG18HN47NJ00D)'          | 'CHIP'         | ''          | ''   | '20150916'  
 '47NH/0.3A'                    | 'SMLF'     | 'EMPTY'  | 'CVA4703JN03'(!)           = ''              | ''                 | 'CVA4703JN03'              |'L0603'| 'NA'                           | 'IO'       | 'IND SMD 47NH 5% 0.3A(LQG18HN47NJ00D)'          | 'CHIP'         | ''          | ''   | '20150916'  
 '0.56UH/25A'                   | 'SMLF'     | 'IND'    | 'CV+56Q0MZ03'(!)           = ''              | ''                 | 'CV+56Q0MZ03'              |'L_PCMC104T'| '0.56UH/25A'                   | 'DISCRETE' | 'IND SMD 0.56U +-20% 25A(PCMC104T-R56MN)'       | 'CHIP'         | ''          | ''   | '20151007'  
 '0.56UH/25A'                   | 'SMLF'     | 'EMPTY'  | 'CV+56Q0MZ03'(!)           = ''              | ''                 | 'CV+56Q0MZ03'              |'L_PCMC104T'| 'NA'                           | 'IO'       | 'IND SMD 0.56U +-20% 25A(PCMC104T-R56MN)'       | 'CHIP'         | ''          | ''   | '20151007'  
 'SBY100505T-121Y-NA/500MA'     | 'SMLF'     | 'IND'    | 'CX05T121002'(!)           = ''              | ''                 | 'CX05T121002'              |'L0402'| 'SBY100505T-121Y-NA/500MA'     | 'DISCRETE' | 'EMI FILTER SBY100505T-121Y-NA(120,500MA)'      | 'CHIP'         | ''          | ''   | '20151015'  
 'SBY100505T-121Y-NA/500MA'     | 'SMLF'     | 'EMPTY'  | 'CX05T121002'(!)           = ''              | ''                 | 'CX05T121002'              |'L0402'| 'NA'                           | 'IO'       | 'EMI FILTER SBY100505T-121Y-NA(120,500MA)'      | 'CHIP'         | ''          | ''   | '20151015'  
 'MMZ2012S601AT/500MA'          | 'SMLF'     | 'IND'    | 'CX12S601003'(!)           = 'End of Design' | 'End of Life'      | 'CX12S601003'              |'L0805_EOL'| 'MMZ2012S601AT/500MA'          | 'DISCRETE' | 'EMI FIL,MMZ2012S601AT,500MA,2012,600/OHM'      | 'CHIP'         | ''          | ''   | '20151029'  
 'MMZ2012S601AT/500MA'          | 'SMLF'     | 'EMPTY'  | 'CX12S601003'(!)           = 'End of Design' | 'End of Life'      | 'CX12S601003'              |'L0805_EOL'| 'NA'                           | 'IO'       | 'EMI FIL,MMZ2012S601AT,500MA,2012,600/OHM'      | 'CHIP'         | ''          | ''   | '20151029'  
 '250NH/38A'                    | 'SMLF'     | 'IND'    | 'CV+25^0KZ04'(!)           = ''              | ''                 | 'CV+25^0KZ04'              |'L_HCUVD6270_6-2X5-5'| '250NH/38A'                    | 'DISCRETE' | 'IND SMD 250NH 10% 38A(HCUVD6270-251LY)'        | 'CHIP'         | ''          | ''   | '20151029'  
 '250NH/38A'                    | 'SMLF'     | 'EMPTY'  | 'CV+25^0KZ04'(!)           = ''              | ''                 | 'CV+25^0KZ04'              |'L_HCUVD6270_6-2X5-5'| 'NA'                           | 'IO'       | 'IND SMD 250NH 10% 38A(HCUVD6270-251LY)'        | 'CHIP'         | ''          | ''   | '20151029'  
 '1UH/17A'                      | 'SMLF'     | 'IND'    | 'CV-10H0KZ00'(!)           = ''              | ''                 | 'CV-10H0KZ00'              |'L_HCUVD8095D-102QL_8X8'| '1UH/17A'                      | 'DISCRETE' | 'IND SMD 1UH 10% 17A(HCUVD8095D-102QL)'         | 'CHIP'         | ''          | ''   | '20151104'  
 '1UH/17A'                      | 'SMLF'     | 'EMPTY'  | 'CV-10H0KZ00'(!)           = ''              | ''                 | 'CV-10H0KZ00'              |'L_HCUVD8095D-102QL_8X8'| 'NA'                           | 'IO'       | 'IND SMD 1UH 10% 17A(HCUVD8095D-102QL)'         | 'CHIP'         | ''          | ''   | '20151104'  
 '1000NH/19A'                   | 'SMLF'     | 'IND'    | 'CV-10J0KZ00'(!)           = ''              | ''                 | 'CV-10J0KZ00'              |'L_HCUVD8095D-102QL_8X8'| '1000NH/19A'                   | 'DISCRETE' | 'IND SMD 1000NH 10% 19A(HCUVD8095-102QL)'       | 'CHIP'         | ''          | ''   | '20151104'  
 '1000NH/19A'                   | 'SMLF'     | 'EMPTY'  | 'CV-10J0KZ00'(!)           = ''              | ''                 | 'CV-10J0KZ00'              |'L_HCUVD8095D-102QL_8X8'| 'NA'                           | 'IO'       | 'IND SMD 1000NH 10% 19A(HCUVD8095-102QL)'       | 'CHIP'         | ''          | ''   | '20151104'  
 '0.6UH/18A'                    | 'SMLF'     | 'IND'    | 'CV+60I0KZ00'(!)           = ''              | 'End of Life'      | 'CV+60I0KZ00'              |'L_HCUVD6595D-601LY_6-5X6-5_EOL'| '0.6UH/18A'                    | 'DISCRETE' | 'IND SMD 0.6UH 10% 18A(HCUVD6595D-601LY)'       | 'CHIP'         | ''          | ''   | '20151104'  
 '0.6UH/18A'                    | 'SMLF'     | 'EMPTY'  | 'CV+60I0KZ00'(!)           = ''              | 'End of Life'      | 'CV+60I0KZ00'              |'L_HCUVD6595D-601LY_6-5X6-5_EOL'| 'NA'                           | 'IO'       | 'IND SMD 0.6UH 10% 18A(HCUVD6595D-601LY)'       | 'CHIP'         | ''          | ''   | '20151104'  
 '600NH/20A'                    | 'SMLF'     | 'IND'    | 'CV+60K0KZ00'(!)           = ''              | ''                 | 'CV+60K0KZ00'              |'L_HCUVD6595D-601LY_6-5X6-5'| '600NH/20A'                    | 'DISCRETE' | 'IND SMD 600NH 10% 20A(HCUVD6595-601LY)'        | 'CHIP'         | ''          | ''   | '20151104'  
 '600NH/20A'                    | 'SMLF'     | 'EMPTY'  | 'CV+60K0KZ00'(!)           = ''              | ''                 | 'CV+60K0KZ00'              |'L_HCUVD6595D-601LY_6-5X6-5'| 'NA'                           | 'IO'       | 'IND SMD 600NH 10% 20A(HCUVD6595-601LY)'        | 'CHIP'         | ''          | ''   | '20151104'  
 '1000NH/12A'                   | 'SMLF'     | 'IND'    | 'CV-10C0KZ00'(!)           = ''              | ''                 | 'CV-10C0KZ00'              |'L_HCUVD6595D-601LY_6-5X6-5'| '1000NH/12A'                   | 'DISCRETE' | 'IND SMD 1000NH 10% 12A(HCUVD6595-102LY)'       | 'CHIP'         | ''          | ''   | '20151104'  
 '1000NH/12A'                   | 'SMLF'     | 'EMPTY'  | 'CV-10C0KZ00'(!)           = ''              | ''                 | 'CV-10C0KZ00'              |'L_HCUVD6595D-601LY_6-5X6-5'| 'NA'                           | 'IO'       | 'IND SMD 1000NH 10% 12A(HCUVD6595-102LY)'       | 'CHIP'         | ''          | ''   | '20151104'  
 '0.1U/7A'                      | 'SMLF'     | 'IND'    | 'CV+1070TZ00'(!)           = ''              | ''                 | 'CV+1070TZ00'              |'L_MLV-YT12N_2-5X2'| '0.1U/7A'                      | 'DISCRETE' | 'IND SMD 0.1U 30% 7A(MLV-YT12NR10N-M3Q)'        | 'CHIP'         | ''          | ''   | '20151116'  
 '0.1U/7A'                      | 'SMLF'     | 'EMPTY'  | 'CV+1070TZ00'(!)           = ''              | ''                 | 'CV+1070TZ00'              |'L_MLV-YT12N_2-5X2'| 'NA'                           | 'IO'       | 'IND SMD 0.1U 30% 7A(MLV-YT12NR10N-M3Q)'        | 'CHIP'         | ''          | ''   | '20151116'  
 '0.24U/4.7A'                   | 'SMLF'     | 'IND'    | 'CV+2447TZ00'(!)           = ''              | ''                 | 'CV+2447TZ00'              |'L_MLV-TP10NR24N-XP_2X1-6'| '0.24U/4.7A'                   | 'DISCRETE' | 'INDSMD 0.24U 30% 4.7A(MLV-TP10NR24N-P4Q'       | 'CHIP'         | ''          | ''   | '20151116'  
 '0.24U/4.7A'                   | 'SMLF'     | 'EMPTY'  | 'CV+2447TZ00'(!)           = ''              | ''                 | 'CV+2447TZ00'              |'L_MLV-TP10NR24N-XP_2X1-6'| 'NA'                           | 'IO'       | 'INDSMD 0.24U 30% 4.7A(MLV-TP10NR24N-P4Q'       | 'CHIP'         | ''          | ''   | '20151116'  
 '35F0121-0SR-10'               | 'SMLF'     | 'IND'    | 'TMP_QCX0F0121000'(!)      = ''              | ''                 | 'CX0F0121000'              |'L_35F0121'| '35F0121-0SR-10 '              | 'DISCRETE' | 'EMI FILTER 35F0121-0SR-10 (42.10A)'            | 'CHIP'         | ''          | ''   | '20151119'  
 '35F0121-0SR-10'               | 'SMLF'     | 'EMPTY'  | 'TMP_QCX0F0121000'(!)      = ''              | ''                 | 'CX0F0121000'              |'L_35F0121'| 'NA'                           | 'IO'       | 'EMI FILTER 35F0121-0SR-10 (42.10A)'            | 'CHIP'         | ''          | ''   | '20151119'  
 '1UH/11A'                      | 'SMLF'     | 'IND'    | 'CV-10B0KZ00'(!)           = ''              | 'End of Life'      | 'CV-10B0KZ00'              |'L_HCUVD6595D-601LY_6-5X6-5_EOL'| '1UH/11A'                      | 'DISCRETE' | 'IND SMD 1UH +-10% 11A(HCUVD6595D-102LY)'       | 'CHIP'         | ''          | ''   | '20151120'  
 '1UH/11A'                      | 'SMLF'     | 'EMPTY'  | 'CV-10B0KZ00'(!)           = ''              | 'End of Life'      | 'CV-10B0KZ00'              |'L_HCUVD6595D-601LY_6-5X6-5_EOL'| 'NA'                           | 'IO'       | 'IND SMD 1UH +-10% 11A(HCUVD6595D-102LY)'       | 'CHIP'         | ''          | ''   | '20151120'  
 '560NH/32A'                    | 'SMLF'     | 'IND'    | 'CV+56X0KZ00'(!)           = ''              | ''                 | 'CV+56X0KZ00'              |'L_HCUVD8083_8X8'| '560NH/32A'                    | 'DISCRETE' | 'IND SMD 560NH 10% 32A(HCUVD8083-561H)'         | 'CHIP'         | ''          | ''   | '20151126'  
 '560NH/32A'                    | 'SMLF'     | 'EMPTY'  | 'CV+56X0KZ00'(!)           = ''              | ''                 | 'CV+56X0KZ00'              |'L_HCUVD8083_8X8'| 'NA'                           | 'IO'       | 'IND SMD 560NH 10% 32A(HCUVD8083-561H)'         | 'CHIP'         | ''          | ''   | '20151126'  
 '940NH/19A'                    | 'SMLF'     | 'IND'    | 'CV+94J0KZ00'(!)           = ''              | ''                 | 'CV+94J0KZ00'              |'L_HCUVD8083_8X8'| '940NH/19A'                    | 'DISCRETE' | 'IND SMD 940NH 10% 19A(HCUVD8083-941H)'         | 'CHIP'         | ''          | ''   | '20151126'  
 '940NH/19A'                    | 'SMLF'     | 'EMPTY'  | 'CV+94J0KZ00'(!)           = ''              | ''                 | 'CV+94J0KZ00'              |'L_HCUVD8083_8X8'| 'NA'                           | 'IO'       | 'IND SMD 940NH 10% 19A(HCUVD8083-941H)'         | 'CHIP'         | ''          | ''   | '20151126'  
 '100NH/80MA'                   | 'SMLF'     | 'IND'    | 'CV+1001JN01'(!)           = ''              | ''                 | 'CV+1001JN01'              |'L0201'| '100NH/80MA'                   | 'DISCRETE' | 'IND CHIP 100N +-5% 80MA LQP03TNR10J02D'        | 'CHIP'         | ''          | ''   | '20151130'  
 '100NH/80MA'                   | 'SMLF'     | 'EMPTY'  | 'CV+1001JN01'(!)           = ''              | ''                 | 'CV+1001JN01'              |'L0201'| 'NA'                           | 'IO'       | 'IND CHIP 100N +-5% 80MA LQP03TNR10J02D'        | 'CHIP'         | ''          | ''   | '20151130'  
 '120NH/40MA'                   | 'SMLF'     | 'IND'    | 'CV+1201JN01'(!)           = ''              | ''                 | 'CV+1201JN01'              |'L0201'| '120NH/40MA'                   | 'DISCRETE' | 'IND CHIP 120N+-5% 40MA LQP03TNR12J02D'         | 'CHIP'         | ''          | ''   | '20151130'  
 '120NH/40MA'                   | 'SMLF'     | 'EMPTY'  | 'CV+1201JN01'(!)           = ''              | ''                 | 'CV+1201JN01'              |'L0201'| 'NA'                           | 'IO'       | 'IND CHIP 120N+-5% 40MA LQP03TNR12J02D'         | 'CHIP'         | ''          | ''   | '20151130'  
 '33NH/120MA'                   | 'SMLF'     | 'IND'    | 'CVA3302JN05'(!)           = ''              | ''                 | 'CVA3302JN05'              |'L0201'| '33NH/120MA'                   | 'DISCRETE' | 'IND CHIP 33N +-5%,120MA(LQP03TN33NJ02D)'       | 'CHIP'         | ''          | ''   | '20151130'  
 '33NH/120MA'                   | 'SMLF'     | 'EMPTY'  | 'CVA3302JN05'(!)           = ''              | ''                 | 'CVA3302JN05'              |'L0201'| 'NA'                           | 'IO'       | 'IND CHIP 33N +-5%,120MA(LQP03TN33NJ02D)'       | 'CHIP'         | ''          | ''   | '20151130'  
 '39NH/120MA'                   | 'SMLF'     | 'IND'    | 'CVA3902JN01'(!)           = ''              | ''                 | 'CVA3902JN01'              |'L0201'| '39NH/120MA'                   | 'DISCRETE' | 'IND CHIP 39N(+-5%,120MA)LQP03TN39NJ02D'        | 'CHIP'         | ''          | ''   | '20151130'  
 '39NH/120MA'                   | 'SMLF'     | 'EMPTY'  | 'CVA3902JN01'(!)           = ''              | ''                 | 'CVA3902JN01'              |'L0201'| 'NA'                           | 'IO'       | 'IND CHIP 39N(+-5%,120MA)LQP03TN39NJ02D'        | 'CHIP'         | ''          | ''   | '20151130'  
 '1NH/750MA'                    | 'SMLF'     | 'IND'    | 'CVB1008TN00'(!)           = ''              | ''                 | 'CVB1008TN00'              |'L0201'| '1NH/750MA'                    | 'DISCRETE' | 'IND CHIP 1NH(+-0.1NH,750MA)LQP03TN1N0B02'      | 'CHIP'         | ''          | ''   | '20151130'  
 '1NH/750MA'                    | 'SMLF'     | 'EMPTY'  | 'CVB1008TN00'(!)           = ''              | ''                 | 'CVB1008TN00'              |'L0201'| 'NA'                           | 'IO'       | 'IND CHIP 1NH(+-0.1NH,750MA)LQP03TN1N0B02'      | 'CHIP'         | ''          | ''   | '20151130'  
 '3NH/450MA'                    | 'SMLF'     | 'IND'    | 'CVB3005BN00'(!)           = ''              | ''                 | 'CVB3005BN00'              |'L0201'| '3NH/450MA'                    | 'DISCRETE' | 'IND CHIP 3N(+-0.1N,450MA)LQP03TN3N0B02D'       | 'CHIP'         | ''          | ''   | '20151130'  
 '3NH/450MA'                    | 'SMLF'     | 'EMPTY'  | 'CVB3005BN00'(!)           = ''              | ''                 | 'CVB3005BN00'              |'L0201'| 'NA'                           | 'IO'       | 'IND CHIP 3N(+-0.1N,450MA)LQP03TN3N0B02D'       | 'CHIP'         | ''          | ''   | '20151130'  
 '100NH/0.15A'                  | 'SMLF'     | 'IND'    | 'CV+1002JN00'(!)           = ''              | ''                 | 'CV+1002JN00'              |'L0402'| '100NH/0.15A'                  | 'DISCRETE' | 'IND CHIP 100N(+-5%,0.15A)LQG15HNR10J02D'       | 'CHIP'         | ''          | ''   | '20151202'  
 '100NH/0.15A'                  | 'SMLF'     | 'EMPTY'  | 'CV+1002JN00'(!)           = ''              | ''                 | 'CV+1002JN00'              |'L0402'| 'NA'                           | 'IO'       | 'IND CHIP 100N(+-5%,0.15A)LQG15HNR10J02D'       | 'CHIP'         | ''          | ''   | '20151202'  
 '1NH/0.3A'                     | 'SMLF'     | 'IND'    | 'CVB1003TN00'(!)           = ''              | ''                 | 'CVB1003TN00'              |'L0402'| '1NH/0.3A'                     | 'DISCRETE' | 'IND CHIP 1N(+-0.3NH,0.3A)LQG15HN1N0S02D'       | 'CHIP'         | ''          | ''   | '20151202'  
 '1NH/0.3A'                     | 'SMLF'     | 'EMPTY'  | 'CVB1003TN00'(!)           = ''              | ''                 | 'CVB1003TN00'              |'L0402'| 'NA'                           | 'IO'       | 'IND CHIP 1N(+-0.3NH,0.3A)LQG15HN1N0S02D'       | 'CHIP'         | ''          | ''   | '20151202'  
 '3NH/300MA'                    | 'SMLF'     | 'IND'    | 'CVB3003TN00'(!)           = ''              | ''                 | 'CVB3003TN00'              |'L0402'| '3NH/300MA'                    | 'DISCRETE' | 'IND CHIP 3NH,+-0.3N,300MA,LQG15HN3N0S02D'      | 'CHIP'         | ''          | ''   | '20151202'  
 '3NH/300MA'                    | 'SMLF'     | 'EMPTY'  | 'CVB3003TN00'(!)           = ''              | ''                 | 'CVB3003TN00'              |'L0402'| 'NA'                           | 'IO'       | 'IND CHIP 3NH,+-0.3N,300MA,LQG15HN3N0S02D'      | 'CHIP'         | ''          | ''   | '20151202'  
 '120NH/150MA'                  | 'SMLF'     | 'IND'    | 'CV+1202JN00'(!)           = ''              | ''                 | 'CV+1202JN00'              |'L0402'| '120NH/150MA'                  | 'DISCRETE' | 'IND CHIP 120NH+-5%,150MA(LQG15HSR12J02D)'      | 'CHIP'         | ''          | ''   | '20151203'  
 '120NH/150MA'                  | 'SMLF'     | 'EMPTY'  | 'CV+1202JN00'(!)           = ''              | ''                 | 'CV+1202JN00'              |'L0402'| 'NA'                           | 'IO'       | 'IND CHIP 120NH+-5%,150MA(LQG15HSR12J02D)'      | 'CHIP'         | ''          | ''   | '20151203'  
 '33NH/200MA'                   | 'SMLF'     | 'IND'    | 'CVA3302JN11'(!)           = ''              | ''                 | 'CVA3302JN11'              |'L0402'| '33NH/200MA'                   | 'DISCRETE' | 'INDUCTOR CHIP 33NH +-5% 200MA,1005'            | 'CHIP'         | ''          | ''   | '20151203'  
 '33NH/200MA'                   | 'SMLF'     | 'EMPTY'  | 'CVA3302JN11'(!)           = ''              | ''                 | 'CVA3302JN11'              |'L0402'| 'NA'                           | 'IO'       | 'INDUCTOR CHIP 33NH +-5% 200MA,1005'            | 'CHIP'         | ''          | ''   | '20151203'  
 '39NH/0.2A'                    | 'SMLF'     | 'IND'    | 'CVA3902JN02'(!)           = ''              | ''                 | 'CVA3902JN02'              |'L0402'| '39NH/0.2A'                    | 'DISCRETE' | 'IND CHIP 39NH5%0.2A,LQG15HS39NJ02D PALAS'      | 'CHIP'         | ''          | ''   | '20151203'  
 '39NH/0.2A'                    | 'SMLF'     | 'EMPTY'  | 'CVA3902JN02'(!)           = ''              | ''                 | 'CVA3902JN02'              |'L0402'| 'NA'                           | 'IO'       | 'IND CHIP 39NH5%0.2A,LQG15HS39NJ02D PALAS'      | 'CHIP'         | ''          | ''   | '20151203'  
 '1UH/24A'                      | 'SMLF'     | 'IND'    | 'CV-10P0MZ03'(!)           = ''              | ''                 | 'CV-10P0MZ03'              |'L_MHD-07EZP_7-2X7-5'| '1UH/24A'                      | 'DISCRETE' | 'IND SMD 1UH 20% 24A(MHD-07EZP1R0M-XCQ)'        | 'CHIP'         | ''          | ''   | '20151209'  
 '1UH/24A'                      | 'SMLF'     | 'EMPTY'  | 'CV-10P0MZ03'(!)           = ''              | ''                 | 'CV-10P0MZ03'              |'L_MHD-07EZP_7-2X7-5'| 'NA'                           | 'IO'       | 'IND SMD 1UH 20% 24A(MHD-07EZP1R0M-XCQ)'        | 'CHIP'         | ''          | ''   | '20151209'  
 '220NH/81A'                    | 'SMLF'     | 'IND'    | 'CV+22^0KZ17'(!)           = 'End of Design' | 'Comp-Approve'     | 'CV+22^0KZ17'              |'L_SI2C100712_10-7X7-5'| '220NH/81A'                    | 'DISCRETE' | 'IND SMD 220NH 10% 81A(SI2C100712-R22K-R1'      | 'CHIP'         | ''          | ''   | '20151209'  
 '220NH/81A'                    | 'SMLF'     | 'EMPTY'  | 'CV+22^0KZ17'(!)           = 'End of Design' | 'Comp-Approve'     | 'CV+22^0KZ17'              |'L_SI2C100712_10-7X7-5'| 'NA'                           | 'IO'       | 'IND SMD 220NH 10% 81A(SI2C100712-R22K-R1'      | 'CHIP'         | ''          | ''   | '20151209'  
 '120NH/94A'                    | 'SMLF'     | 'IND'    | 'CV+12^0KZ05'(!)           = 'End of Design' | 'Comp-Approve'     | 'CV+12^0KZ05'              |'L_HCUVE966490D-121'| '120NH/94A'                    | 'DISCRETE' | 'IND SMD 120NH 10% 94A(HCUVE966490D-121)'       | 'CHIP'         | ''          | ''   | '20151221'  
 '120NH/94A'                    | 'SMLF'     | 'EMPTY'  | 'CV+12^0KZ05'(!)           = 'End of Design' | 'Comp-Approve'     | 'CV+12^0KZ05'              |'L_HCUVE966490D-121'| 'NA'                           | 'IO'       | 'IND SMD 120NH 10% 94A(HCUVE966490D-121)'       | 'CHIP'         | ''          | ''   | '20151221'  
 '150NH/75A'                    | 'SMLF'     | 'IND'    | 'CV+15^0KZ08'(!)           = 'End of Design' | 'Comp-Approve'     | 'CV+15^0KZ08'              |'L_HCUVE966490D-121'| '150NH/75A'                    | 'DISCRETE' | 'IND SMD 150NH 10% 75A(HCUVE966490D-151)'       | 'CHIP'         | ''          | ''   | '20151221'  
 '150NH/75A'                    | 'SMLF'     | 'EMPTY'  | 'CV+15^0KZ08'(!)           = 'End of Design' | 'Comp-Approve'     | 'CV+15^0KZ08'              |'L_HCUVE966490D-121'| 'NA'                           | 'IO'       | 'IND SMD 150NH 10% 75A(HCUVE966490D-151)'       | 'CHIP'         | ''          | ''   | '20151221'  
 '300NH/33A'                    | 'SMLF'     | 'IND'    | 'CV+30Y0KZ00'(!)           = 'End of Design' | 'Comp-Approve'     | 'CV+30Y0KZ00'              |'L_HCUVE966490D-121'| '300NH/33A'                    | 'DISCRETE' | 'IND SMD 300NH 10% 33A(HCUVE966490D-301)'       | 'CHIP'         | ''          | ''   | '20151221'  
 '300NH/33A'                    | 'SMLF'     | 'EMPTY'  | 'CV+30Y0KZ00'(!)           = 'End of Design' | 'Comp-Approve'     | 'CV+30Y0KZ00'              |'L_HCUVE966490D-121'| 'NA'                           | 'IO'       | 'IND SMD 300NH 10% 33A(HCUVE966490D-301)'       | 'CHIP'         | ''          | ''   | '20151221'  
 '0.22UH/53A'                   | 'SMLF'     | 'IND'    | 'CV+22^0MZ26'(!)           = ''              | ''                 | 'CV+22^0MZ26'              |'L_MMD12FD'| '0.22UH/53A'                   | 'DISCRETE' | 'IND SMD 0.22UH 20% 53A(MMD-12FD-R22M-V1Q'      | 'CHIP'         | ''          | ''   | '20151223'  
 '0.22UH/53A'                   | 'SMLF'     | 'EMPTY'  | 'CV+22^0MZ26'(!)           = ''              | ''                 | 'CV+22^0MZ26'              |'L_MMD12FD'| 'NA'                           | 'IO'       | 'IND SMD 0.22UH 20% 53A(MMD-12FD-R22M-V1Q'      | 'CHIP'         | ''          | ''   | '20151223'  
 '80NH/52A'                     | 'SMLF'     | 'IND'    | 'CVA80^0EZ00'(!)           = ''              | ''                 | 'CVA80^0EZ00'              |'L_SL2026-R08LHF'| '80NH/52A'                     | 'DISCRETE' | 'IND SMD 80NH 15% 52A(SL2026-R08LHF)'           | 'CHIP'         | ''          | ''   | '20151228'  
 '80NH/52A'                     | 'SMLF'     | 'EMPTY'  | 'CVA80^0EZ00'(!)           = ''              | ''                 | 'CVA80^0EZ00'              |'L_SL2026-R08LHF'| 'NA'                           | 'IO'       | 'IND SMD 80NH 15% 52A(SL2026-R08LHF)'           | 'CHIP'         | ''          | ''   | '20151228'  
 '1.5UH/27A'                    | 'SMLF'     | 'IND'    | 'CV-15S0MZ01'(!)           = ''              | ''                 | 'CV-15S0MZ01'              |'L_MMD12FD'| '1.5UH/27A'                    | 'DISCRETE' | 'IND SMD 1.5UH 20% 27A(MMD-12FD-1R5M-B1Q)'      | 'CHIP'         | ''          | ''   | '20151231'  
 '1.5UH/27A'                    | 'SMLF'     | 'EMPTY'  | 'CV-15S0MZ01'(!)           = ''              | ''                 | 'CV-15S0MZ01'              |'L_MMD12FD'| 'NA'                           | 'IO'       | 'IND SMD 1.5UH 20% 27A(MMD-12FD-1R5M-B1Q)'      | 'CHIP'         | ''          | ''   | '20151231'  
 '100NH/16A'                    | 'SMLF'     | 'IND'    | 'CV+10G0MZ05'(!)           = ''              | ''                 | 'CV+10G0MZ05'              |'L_HCBS404045_4X4'| '100NH/16A'                    | 'DISCRETE' | 'IND SMD 100NH 20% 16A(HCBS404045-101)'         | 'CHIP'         | ''          | ''   | '20160104'  
 '100NH/16A'                    | 'SMLF'     | 'EMPTY'  | 'CV+10G0MZ05'(!)           = ''              | ''                 | 'CV+10G0MZ05'              |'L_HCBS404045_4X4'| 'NA'                           | 'IO'       | 'IND SMD 100NH 20% 16A(HCBS404045-101)'         | 'CHIP'         | ''          | ''   | '20160104'  
 '80NH/50A'                     | 'SMLF'     | 'IND'    | 'CVA80^0MZ01'(!)           = ''              | ''                 | 'CVA80^0MZ01'              |'L_HCBS5265_5-2X5-2'| '80NH/50A'                     | 'DISCRETE' | 'IND SMD 80NH 20% 50A(HCBS5265-800)'            | 'CHIP'         | ''          | ''   | '20160104'  
 '80NH/50A'                     | 'SMLF'     | 'EMPTY'  | 'CVA80^0MZ01'(!)           = ''              | ''                 | 'CVA80^0MZ01'              |'L_HCBS5265_5-2X5-2'| 'NA'                           | 'IO'       | 'IND SMD 80NH 20% 50A(HCBS5265-800)'            | 'CHIP'         | ''          | ''   | '20160104'  
 'BLM18SN220TN1D/8000MA'        | 'SMLF'     | 'IND'    | 'CX220TN1001'(!)           = 'End of Design' | 'Comp-Approve'     | 'CX220TN1001'              |'L0603'| 'BLM18SN220TN1D/8000MA'        | 'DISCRETE' | 'EMI FILTER BLM18SN220TN1D(22,8000MA)'          | 'CHIP'         | ''          | ''   | '20160104'  
 'BLM18SN220TN1D/8000MA'        | 'SMLF'     | 'EMPTY'  | 'CX220TN1001'(!)           = 'End of Design' | 'Comp-Approve'     | 'CX220TN1001'              |'L0603'| 'NA'                           | 'IO'       | 'EMI FILTER BLM18SN220TN1D(22,8000MA)'          | 'CHIP'         | ''          | ''   | '20160104'  
 '0.88UH/20A'                   | 'SMLF'     | 'IND'    | 'CV+88K0MZ01'(!)           = ''              | ''                 | 'CV+88K0MZ01'              |'L_PCMC104T'| '0.88UH/20A'                   | 'DISCRETE' | 'IND SMD 0.88UH +-20% 20A(PCMC104T-R88MN)'      | 'CHIP'         | ''          | ''   | '20160112'  
 '0.88UH/20A'                   | 'SMLF'     | 'EMPTY'  | 'CV+88K0MZ01'(!)           = ''              | ''                 | 'CV+88K0MZ01'              |'L_PCMC104T'| 'NA'                           | 'IO'       | 'IND SMD 0.88UH +-20% 20A(PCMC104T-R88MN)'      | 'CHIP'         | ''          | ''   | '20160112'  
 'FBMJ2125HS250NT/6A'           | 'SMLF'     | 'IND'    | 'CX0250NT006'(!)           = 'End of Design' | 'Comp-Approve'     | 'CX0250NT006'              |'L0805'| 'FBMJ2125HS250NT/6A'           | 'DISCRETE' | 'EMI FILTER CHIP FBMJ2125HS250NT(25,6A)'        | 'CHIP'         | ''          | ''   | '20160120'  
 'FBMJ2125HS250NT/6A'           | 'SMLF'     | 'EMPTY'  | 'CX0250NT006'(!)           = 'End of Design' | 'Comp-Approve'     | 'CX0250NT006'              |'L0805'| 'NA'                           | 'IO'       | 'EMI FILTER CHIP FBMJ2125HS250NT(25,6A)'        | 'CHIP'         | ''          | ''   | '20160120'  
 '2.2UH/5.6A'                   | 'SMLF'     | 'IND'    | 'CV-2256MZ00'(!)           = ''              | ''                 | 'CV-2256MZ00'              |'L_XAL4020-222MEC'| '2.2UH/5.6A'                   | 'DISCRETE' | 'IND SMD 2.2U 20% 5.6A(XAL4020-222MEC)AEC'      | 'CHIP'         | ''          | ''   | '20160203'  
 '2.2UH/5.6A'                   | 'SMLF'     | 'EMPTY'  | 'CV-2256MZ00'(!)           = ''              | ''                 | 'CV-2256MZ00'              |'L_XAL4020-222MEC'| 'NA'                           | 'IO'       | 'IND SMD 2.2U 20% 5.6A(XAL4020-222MEC)AEC'      | 'CHIP'         | ''          | ''   | '20160203'  
 '120NH/94A'                    | 'SMLF'     | 'IND'    | 'CV+12^0KZ06'(!)           = 'End of Design' | 'Comp-Approve'     | 'CV+12^0KZ06'              |'L_SLA3735B'| '120NH/94A'                    | 'DISCRETE' | 'IND SMD 120NH 10% 94A(SLA3735B-120K)'          | 'CHIP'         | ''          | ''   | '20160203'  
 '120NH/94A'                    | 'SMLF'     | 'EMPTY'  | 'CV+12^0KZ06'(!)           = 'End of Design' | 'Comp-Approve'     | 'CV+12^0KZ06'              |'L_SLA3735B'| 'NA'                           | 'IO'       | 'IND SMD 120NH 10% 94A(SLA3735B-120K)'          | 'CHIP'         | ''          | ''   | '20160203'  
 '150NH/75A'                    | 'SMLF'     | 'IND'    | 'CV+15^0KZ09'(!)           = 'End of Design' | 'Comp-Approve'     | 'CV+15^0KZ09'              |'L_SLA3735B'| '150NH/75A'                    | 'DISCRETE' | 'IND SMD 150NH 10% 75A(SLA3735B-150K)'          | 'CHIP'         | ''          | ''   | '20160203'  
 '150NH/75A'                    | 'SMLF'     | 'EMPTY'  | 'CV+15^0KZ09'(!)           = 'End of Design' | 'Comp-Approve'     | 'CV+15^0KZ09'              |'L_SLA3735B'| 'NA'                           | 'IO'       | 'IND SMD 150NH 10% 75A(SLA3735B-150K)'          | 'CHIP'         | ''          | ''   | '20160203'  
 '300NH/33A'                    | 'SMLF'     | 'IND'    | 'CV+30Y0KZ01'(!)           = 'End of Design' | 'Comp-Approve'     | 'CV+30Y0KZ01'              |'L_SLA3735B'| '300NH/33A'                    | 'DISCRETE' | 'IND SMD 300NH 10% 33A(SLA3735B-300K)'          | 'CHIP'         | ''          | ''   | '20160203'  
 '300NH/33A'                    | 'SMLF'     | 'EMPTY'  | 'CV+30Y0KZ01'(!)           = 'End of Design' | 'Comp-Approve'     | 'CV+30Y0KZ01'              |'L_SLA3735B'| 'NA'                           | 'IO'       | 'IND SMD 300NH 10% 33A(SLA3735B-300K)'          | 'CHIP'         | ''          | ''   | '20160203'  
 '2.2UH/45A'                    | 'SMLF'     | 'IND'    | 'CV-22^0MZ04'(!)           = ''              | ''                 | 'CV-22^0MZ04'              |'L_MSE-12FDE_13-2X12-9'| '2.2UH/45A'                    | 'DISCRETE' | 'IND SMD 2.2UH 20% 45A(MSE-12FDE2R2M-M1Q)'      | 'CHIP'         | ''          | ''   | '20160204'  
 '2.2UH/45A'                    | 'SMLF'     | 'EMPTY'  | 'CV-22^0MZ04'(!)           = ''              | ''                 | 'CV-22^0MZ04'              |'L_MSE-12FDE_13-2X12-9'| 'NA'                           | 'IO'       | 'IND SMD 2.2UH 20% 45A(MSE-12FDE2R2M-M1Q)'      | 'CHIP'         | ''          | ''   | '20160204'  
 '600NH/18A'                    | 'SMLF'     | 'IND'    | 'CV+60I0KZ01'(!)           = 'End of Design' | 'Comp-Approve'     | 'CV+60I0KZ01'              |'L_HCUVD6595D-601KLY_6-5X6-5'| '600NH/18A'                    | 'DISCRETE' | 'IND SMD 600NH 10% 18A(HCUVD6595D-601KLY)'      | 'CHIP'         | ''          | ''   | '20160204'  
 '600NH/18A'                    | 'SMLF'     | 'EMPTY'  | 'CV+60I0KZ01'(!)           = 'End of Design' | 'Comp-Approve'     | 'CV+60I0KZ01'              |'L_HCUVD6595D-601KLY_6-5X6-5'| 'NA'                           | 'IO'       | 'IND SMD 600NH 10% 18A(HCUVD6595D-601KLY)'      | 'CHIP'         | ''          | ''   | '20160204'  
 '1UH/11A'                      | 'SMLF'     | 'IND'    | 'CV-10B0KZ01'(!)           = 'End of Design' | 'Comp-Approve'     | 'CV-10B0KZ01'              |'L_HCUVD6595D-601KLY_6-5X6-5'| '1UH/11A'                      | 'DISCRETE' | 'IND SMD 1UH 10% 11A(HCUVD6595D-102KLY)'        | 'CHIP'         | ''          | ''   | '20160204'  
 '1UH/11A'                      | 'SMLF'     | 'EMPTY'  | 'CV-10B0KZ01'(!)           = 'End of Design' | 'Comp-Approve'     | 'CV-10B0KZ01'              |'L_HCUVD6595D-601KLY_6-5X6-5'| 'NA'                           | 'IO'       | 'IND SMD 1UH 10% 11A(HCUVD6595D-102KLY)'        | 'CHIP'         | ''          | ''   | '20160204'  
 '0.1UH/16A'                    | 'SMLF'     | 'IND'    | 'CV+10G0MZ06'(!)           = 'End of Design' | 'Comp-Approve'     | 'CV+10G0MZ06'              |'L_L30909-64_4X4'| '0.1UH/16A'                    | 'DISCRETE' | 'IND SMD 0.1UH 20% 16A(L30909-64)'              | 'CHIP'         | ''          | ''   | '20160215'  
 '0.1UH/16A'                    | 'SMLF'     | 'EMPTY'  | 'CV+10G0MZ06'(!)           = 'End of Design' | 'Comp-Approve'     | 'CV+10G0MZ06'              |'L_L30909-64_4X4'| 'NA'                           | 'IO'       | 'IND SMD 0.1UH 20% 16A(L30909-64)'              | 'CHIP'         | ''          | ''   | '20160215'  
 '0.08UH/50A'                   | 'SMLF'     | 'IND'    | 'CVA80^0EZ01'(!)           = 'End of Design' | 'Comp-Approve'     | 'CVA80^0EZ01'              |'L_L30909-63_5-2X5-2'| '0.08UH/50A'                   | 'DISCRETE' | 'IND SMD 0.08UH 15% 50A(L30909-63)'             | 'CHIP'         | ''          | ''   | '20160215'  
 '0.08UH/50A'                   | 'SMLF'     | 'EMPTY'  | 'CVA80^0EZ01'(!)           = 'End of Design' | 'Comp-Approve'     | 'CVA80^0EZ01'              |'L_L30909-63_5-2X5-2'| 'NA'                           | 'IO'       | 'IND SMD 0.08UH 15% 50A(L30909-63)'             | 'CHIP'         | ''          | ''   | '20160215'  
 '2.2UH/50A'                    | 'SMLF'     | 'IND'    | 'CV-22^0MZ05'(!)           = ''              | ''                 | 'CV-22^0MZ05'              |'L_MSE-12FDE_13-2X12-9_H315'| '2.2UH/50A'                    | 'DISCRETE' | 'IND SMD 2.2UH 20% 50A(MSE-12HZE2R2M-M1Q)'      | 'CHIP'         | ''          | ''   | '20160215'  
 '2.2UH/50A'                    | 'SMLF'     | 'EMPTY'  | 'CV-22^0MZ05'(!)           = ''              | ''                 | 'CV-22^0MZ05'              |'L_MSE-12FDE_13-2X12-9_H315'| 'NA'                           | 'IO'       | 'IND SMD 2.2UH 20% 50A(MSE-12HZE2R2M-M1Q)'      | 'CHIP'         | ''          | ''   | '20160215'  
 'BLM41PG181SN1L/3.5A'          | 'SMLF'     | 'IND'    | 'CX1PG181000'(!)           = ''              | ''                 | 'CX1PG181000'              |'L1806'| 'BLM41PG181SN1L/3.5A'          | 'DISCRETE' | 'EMI FILTER BLM41PG181SN1L(180,3.5A)'           | 'CHIP'         | ''          | ''   | '20160216'  
 'BLM41PG181SN1L/3.5A'          | 'SMLF'     | 'EMPTY'  | 'CX1PG181000'(!)           = ''              | ''                 | 'CX1PG181000'              |'L1806'| 'NA'                           | 'IO'       | 'EMI FILTER BLM41PG181SN1L(180,3.5A)'           | 'CHIP'         | ''          | ''   | '20160216'  
 '1UH/17A'                      | 'SMLF'     | 'IND'    | 'CV-10H0KZ01'(!)           = ''              | ''                 | 'CV-10H0KZ01'              |'L_HCUVD8095D-102KQL_8X8'| '1UH/17A'                      | 'DISCRETE' | 'IND SMD 1UH 10% 17A(HCUVD8095D-102KQL)'        | 'CHIP'         | ''          | ''   | '20160216'  
 '1UH/17A'                      | 'SMLF'     | 'EMPTY'  | 'CV-10H0KZ01'(!)           = ''              | ''                 | 'CV-10H0KZ01'              |'L_HCUVD8095D-102KQL_8X8'| 'NA'                           | 'IO'       | 'IND SMD 1UH 10% 17A(HCUVD8095D-102KQL)'        | 'CHIP'         | ''          | ''   | '20160216'  
 '4.7UH/650MA'                  | 'SMLF'     | 'IND'    | 'CV-4707MZ01'(!)           = 'End of Design' | 'Comp-Approve'     | 'CV-4707MZ01'              |'L1210XC'| '4.7UH'                        | 'DISCRETE' | 'IND SMD 4.7UH 20% 650MA(LQH32CN4R7M33L)'       | 'CHIP'         | ''          | ''   | '20160218'  
 '4.7UH/650MA'                  | 'SMLF'     | 'EMPTY'  | 'CV-4707MZ01'(!)           = 'End of Design' | 'Comp-Approve'     | 'CV-4707MZ01'              |'L1210XC'| 'NA'                           | 'IO'       | 'IND SMD 4.7UH 20% 650MA(LQH32CN4R7M33L)'       | 'CHIP'         | ''          | ''   | '20160218'  
 '0.24UH/4.7A'                  | 'SMLF'     | 'IND'    | 'CV+2447MZ00'(!)           = ''              | ''                 | 'CV+2447MZ00'              |'L_HTTN20161T-R24MDR'| '0.24UH/4.7A'                  | 'DISCRETE' | 'IND SMD 0.24U 20% 4.7A(HTTN20161T-R24MDR'      | 'CHIP'         | ''          | ''   | '20160222'  
 '0.24UH/4.7A'                  | 'SMLF'     | 'EMPTY'  | 'CV+2447MZ00'(!)           = ''              | ''                 | 'CV+2447MZ00'              |'L_HTTN20161T-R24MDR'| 'NA'                           | 'IO'       | 'IND SMD 0.24U 20% 4.7A(HTTN20161T-R24MDR'      | 'CHIP'         | ''          | ''   | '20160222'  
 'PBY160808T-601Y-N(600/1A)'    | 'SMLF'     | 'IND'    | 'CX08T601000'(!)           = ''              | ''                 | 'CX08T601000'              |'L0603'| 'PBY160808T-601Y-N(600/1A)'    | 'DISCRETE' | 'EMI FILTER PBY160808T-601Y-N(600.1A)'          | 'CHIP'         | ''          | ''   | '20160222'  
 'PBY160808T-601Y-N(600/1A)'    | 'SMLF'     | 'EMPTY'  | 'CX08T601000'(!)           = ''              | ''                 | 'CX08T601000'              |'L0603'| 'NA'                           | 'IO'       | 'EMI FILTER PBY160808T-601Y-N(600.1A)'          | 'CHIP'         | ''          | ''   | '20160222'  
 'GMLB-201209-0330P-N8(330/3A)' | 'SMLF'     | 'IND'    | 'CX090330000'(!)           = ''              | ''                 | 'CX090330000'              |'L0805'| 'GMLB-201209-0330P-N8(330/3A)' | 'DISCRETE' | 'EMI FILTER GMLB-201209-0330P-N8(330,3A)'       | 'CHIP'         | ''          | ''   | '20160222'  
 'GMLB-201209-0330P-N8(330/3A)' | 'SMLF'     | 'EMPTY'  | 'CX090330000'(!)           = ''              | ''                 | 'CX090330000'              |'L0805'| 'NA'                           | 'IO'       | 'EMI FILTER GMLB-201209-0330P-N8(330,3A)'       | 'CHIP'         | ''          | ''   | '20160222'  
 'GMLB-201209-0600P-N8/2A'      | 'SMLF'     | 'IND'    | 'CX090600001'(!)           = ''              | 'End of Life'      | 'CX090600001'              |'L0805_EOL'| 'GMLB-201209-0600P-N8/2A'      | 'DISCRETE' | 'EMI FILTER GMLB-201209-0600P-N8(600,2A)'       | 'CHIP'         | ''          | ''   | '20160223'  
 'GMLB-201209-0600P-N8/2A'      | 'SMLF'     | 'EMPTY'  | 'CX090600001'(!)           = ''              | 'End of Life'      | 'CX090600001'              |'L0805_EOL'| 'NA'                           | 'IO'       | 'EMI FILTER GMLB-201209-0600P-N8(600,2A)'       | 'CHIP'         | ''          | ''   | '20160223'  
 'UPB201209T-300Y-N/5A'         | 'SMLF'     | 'IND'    | 'CX09T300012'(!)           = ''              | ''                 | 'CX09T300012'              |'L0805'| 'UPB201209T-300Y-N/5A'         | 'DISCRETE' | 'EMI FILTER UPB201209T-300Y-N(30,5A)'           | 'CHIP'         | ''          | ''   | '20160223'  
 'UPB201209T-300Y-N/5A'         | 'SMLF'     | 'EMPTY'  | 'CX09T300012'(!)           = ''              | ''                 | 'CX09T300012'              |'L0805'| 'NA'                           | 'IO'       | 'EMI FILTER UPB201209T-300Y-N(30,5A)'           | 'CHIP'         | ''          | ''   | '20160223'  
 'BLM18KG300TN1D/5A'            | 'SMLF'     | 'IND'    | 'CX8KG300001'(!)           = ''              | ''                 | 'CX8KG300001'              |'L0603'| 'BLM18KG300TN1D/5A'            | 'DISCRETE' | 'EMI FILTER BLM18KG300TN1D(30,5A)'              | 'CHIP'         | ''          | ''   | '20160223'  
 'BLM18KG300TN1D/5A'            | 'SMLF'     | 'EMPTY'  | 'CX8KG300001'(!)           = ''              | ''                 | 'CX8KG300001'              |'L0603'| 'NA'                           | 'IO'       | 'EMI FILTER BLM18KG300TN1D(30,5A)'              | 'CHIP'         | ''          | ''   | '20160223'  
 '0.24UH/4.4A'                  | 'SMLF'     | 'IND'    | 'CV+2444TZ00'(!)           = ''              | ''                 | 'CV+2444TZ00'              |'L_MLV-TP10NR24N-XP_2X1-6'| '0.24UH/4.4A'                  | 'DISCRETE' | 'IND SMD 0.24UH30% 4.4A MLV-TP10NR24N-XPQ'      | 'CHIP'         | ''          | ''   | '20160302'  
 '0.24UH/4.4A'                  | 'SMLF'     | 'EMPTY'  | 'CV+2444TZ00'(!)           = ''              | ''                 | 'CV+2444TZ00'              |'L_MLV-TP10NR24N-XP_2X1-6'| 'NA'                           | 'IO'       | 'IND SMD 0.24UH30% 4.4A MLV-TP10NR24N-XPQ'      | 'CHIP'         | ''          | ''   | '20160302'  
 '210NH/47A'                    | 'SMLF'     | 'IND'    | 'CV+21^0KZ00'(!)           = ''              | ''                 | 'CV+21^0KZ00'              |'L_HCUVE966490D-121'| '210NH/47A'                    | 'DISCRETE' | 'IND SMD 210NH 10% 47A(HCUVE966490D-211)'       | 'CHIP'         | ''          | ''   | '20160302'  
 '210NH/47A'                    | 'SMLF'     | 'EMPTY'  | 'CV+21^0KZ00'(!)           = ''              | ''                 | 'CV+21^0KZ00'              |'L_HCUVE966490D-121'| 'NA'                           | 'IO'       | 'IND SMD 210NH 10% 47A(HCUVE966490D-211)'       | 'CHIP'         | ''          | ''   | '20160302'  
 '2.2UH/2.5A'                   | 'SMLF'     | 'IND'    | 'CV-2225MZ02'(!)           = ''              | ''                 | 'CV-2225MZ02'              |'L_LVS404018_4X4'| '2.2UH/2.5A'                   | 'DISCRETE' | 'IND SMD 2.2UH 20% 2.5A(LVS404018-2R2M-N)'      | 'CHIP'         | ''          | ''   | '20160303'  
 '2.2UH/2.5A'                   | 'SMLF'     | 'EMPTY'  | 'CV-2225MZ02'(!)           = ''              | ''                 | 'CV-2225MZ02'              |'L_LVS404018_4X4'| 'NA'                           | 'IO'       | 'IND SMD 2.2UH 20% 2.5A(LVS404018-2R2M-N)'      | 'CHIP'         | ''          | ''   | '20160303'  
 '250NH/38A'                    | 'SMLF'     | 'IND'    | 'CV+25^0KZ05'(!)           = ''              | ''                 | 'CV+25^0KZ05'              |'L_HCUVD6270_6-2X5-5XA'| '250NH/38A'                    | 'DISCRETE' | 'IND SMD 250NH 10% 38A(HCUVD6270-251KLY)'       | 'CHIP'         | ''          | ''   | '20160329'  
 '250NH/38A'                    | 'SMLF'     | 'EMPTY'  | 'CV+25^0KZ05'(!)           = ''              | ''                 | 'CV+25^0KZ05'              |'L_HCUVD6270_6-2X5-5XA'| 'NA'                           | 'IO'       | 'IND SMD 250NH 10% 38A(HCUVD6270-251KLY)'       | 'CHIP'         | ''          | ''   | '20160329'  
 '4.7UH/650MA'                  | 'SMLF'     | 'IND'    | 'CV-4707MZ19'(!)           = ''              | ''                 | 'CV-4707MZ19'              |'L1210XC'| '4.7UH/650MA'                  | 'DISCRETE' | 'INDSMD 4.7U 20% 650MA(LQH32CH4R7M33L)AEC'      | 'CHIP'         | ''          | ''   | '20160330'  
 '4.7UH/650MA'                  | 'SMLF'     | 'EMPTY'  | 'CV-4707MZ19'(!)           = ''              | ''                 | 'CV-4707MZ19'              |'L1210XC'| 'NA'                           | 'IO'       | 'INDSMD 4.7U 20% 650MA(LQH32CH4R7M33L)AEC'      | 'CHIP'         | ''          | ''   | '20160330'  
 'BLM18PG121SZ1D/2A'            | 'SMLF'     | 'IND'    | 'CX000121002'(!)           = ''              | ''                 | 'CX000121002'              |'L0603'| 'BLM18PG121SZ1D/2A'            | 'DISCRETE' | 'EMI FILTER BLM18PG121SZ1D(120,2A)AEC'          | 'CHIP'         | ''          | ''   | '20160330'  
 'BLM18PG121SZ1D/2A'            | 'SMLF'     | 'EMPTY'  | 'CX000121002'(!)           = ''              | ''                 | 'CX000121002'              |'L0603'| 'NA'                           | 'IO'       | 'EMI FILTER BLM18PG121SZ1D(120,2A)AEC'          | 'CHIP'         | ''          | ''   | '20160330'  
 'BLM21PG331SZ1D/1.5A'          | 'SMLF'     | 'IND'    | 'CX000331004'(!)           = ''              | ''                 | 'CX000331004'              |'L0805'| 'BLM21PG331SZ1D/1.5A'          | 'DISCRETE' | 'EMI FILTER BLM21PG331SZ1D(330,1.5A)AEC'        | 'CHIP'         | ''          | ''   | '20160330'  
 'BLM21PG331SZ1D/1.5A'          | 'SMLF'     | 'EMPTY'  | 'CX000331004'(!)           = ''              | ''                 | 'CX000331004'              |'L0805'| 'NA'                           | 'IO'       | 'EMI FILTER BLM21PG331SZ1D(330,1.5A)AEC'        | 'CHIP'         | ''          | ''   | '20160330'  
 'BLM21AG601SZ1D/0.7A'          | 'SMLF'     | 'IND'    | 'CX000601003'(!)           = ''              | ''                 | 'CX000601003'              |'L0805'| 'BLM21AG601SZ1D/0.7A'          | 'DISCRETE' | 'EMI FILTER BLM21AG601SZ1D(600,0.7A)AEC'        | 'CHIP'         | ''          | ''   | '20160330'  
 'BLM21AG601SZ1D/0.7A'          | 'SMLF'     | 'EMPTY'  | 'CX000601003'(!)           = ''              | ''                 | 'CX000601003'              |'L0805'| 'NA'                           | 'IO'       | 'EMI FILTER BLM21AG601SZ1D(600,0.7A)AEC'        | 'CHIP'         | ''          | ''   | '20160330'  
 'SMB-853025/10A'               | 'SMLF'     | 'IND'    | 'CX853025000'(!)           = ''              | ''                 | 'CX853025000'              |'L_SMB-853025'| 'SMB-853025/10A'               | 'DISCRETE' | 'EMI FILTER SMB-853025 (90,10A)'                | 'CHIP'         | ''          | ''   | '20160408'  
 'SMB-853025/10A'               | 'SMLF'     | 'EMPTY'  | 'CX853025000'(!)           = ''              | ''                 | 'CX853025000'              |'L_SMB-853025'| 'NA'                           | 'IO'       | 'EMI FILTER SMB-853025 (90,10A)'                | 'CHIP'         | ''          | ''   | '20160408'  
 '1UH/17A'                      | 'SMLF'     | 'IND'    | 'CV-10H0KZ02'(!)           = 'End of Design' | 'Comp-Approve'     | 'CV-10H0KZ02'              |'L_HCUVD8095D-102KBQL_8X8'| '1UH/17A'                      | 'DISCRETE' | 'IND SMD 1UH 10% 17A(HCUVD8095D-102KBQL)'       | 'CHIP'         | ''          | ''   | '20160408'  
 '1UH/17A'                      | 'SMLF'     | 'EMPTY'  | 'CV-10H0KZ02'(!)           = 'End of Design' | 'Comp-Approve'     | 'CV-10H0KZ02'              |'L_HCUVD8095D-102KBQL_8X8'| 'NA'                           | 'IO'       | 'IND SMD 1UH 10% 17A(HCUVD8095D-102KBQL)'       | 'CHIP'         | ''          | ''   | '20160408'  
 '940NH/19A'                    | 'SMLF'     | 'IND'    | 'CV+94J0KZ01'(!)           = ''              | ''                 | 'CV+94J0KZ01'              |'L_HCUVD8083_8X8'| '940NH/19A'                    | 'DISCRETE' | 'IND SMD 940NH 10% 19A(HCUVD8083-941HK)'        | 'CHIP'         | ''          | ''   | '20160414'  
 '940NH/19A'                    | 'SMLF'     | 'EMPTY'  | 'CV+94J0KZ01'(!)           = ''              | ''                 | 'CV+94J0KZ01'              |'L_HCUVD8083_8X8'| 'NA'                           | 'IO'       | 'IND SMD 940NH 10% 19A(HCUVD8083-941HK)'        | 'CHIP'         | ''          | ''   | '20160414'  
 '560NH/32A'                    | 'SMLF'     | 'IND'    | 'CV+56X0KZ01'(!)           = ''              | ''                 | 'CV+56X0KZ01'              |'L_HCUVD8083_8X8'| '560NH/32A'                    | 'DISCRETE' | 'IND SMD 560NH 10% 32A(HCUVD8083-561HK)'        | 'CHIP'         | ''          | ''   | '20160414'  
 '560NH/32A'                    | 'SMLF'     | 'EMPTY'  | 'CV+56X0KZ01'(!)           = ''              | ''                 | 'CV+56X0KZ01'              |'L_HCUVD8083_8X8'| 'NA'                           | 'IO'       | 'IND SMD 560NH 10% 32A(HCUVD8083-561HK)'        | 'CHIP'         | ''          | ''   | '20160414'  
 'FCM1608KF-470T05/0.5A'        | 'SMLF'     | 'IND'    | 'CX470T05000'(!)           = ''              | ''                 | 'CX470T05000'              |'L0603'| 'FCM1608KF-470T05/0.5A'        | 'DISCRETE' | 'EMI FILTER FCM1608KF-470T05(47,0.5A)'          | 'CHIP'         | ''          | ''   | '20160415'  
 'FCM1608KF-470T05/0.5A'        | 'SMLF'     | 'EMPTY'  | 'CX470T05000'(!)           = ''              | ''                 | 'CX470T05000'              |'L0603'| 'NA'                           | 'IO'       | 'EMI FILTER FCM1608KF-470T05(47,0.5A)'          | 'CHIP'         | ''          | ''   | '20160415'  
 'BLM15PX121SN1D/2A'            | 'SMLF'     | 'IND'    | 'CX5PX121001'(!)           = ''              | ''                 | 'CX5PX121001'              |'L0402'| 'BLM15PX121SN1D/2A'            | 'DISCRETE' | 'EMI FILTER BLM15PX121SN1D(120,2A)'             | 'CHIP'         | ''          | ''   | '20160425'  
 'BLM15PX121SN1D/2A'            | 'SMLF'     | 'EMPTY'  | 'CX5PX121001'(!)           = ''              | ''                 | 'CX5PX121001'              |'L0402'| 'NA'                           | 'IO'       | 'EMI FILTER BLM15PX121SN1D(120,2A)'             | 'CHIP'         | ''          | ''   | '20160425'  
 '1.5UH/4A'                     | 'SMLF'     | 'IND'    | 'DC-1540M000'(!)           = ''              | ''                 | 'DC-1540M000'              |'L_PCMB042T'| '1.5UH/4A'                     | 'DISCRETE' | 'CHOKE 1.5UH +-20% 4A(PCMB042T-1R5MS)'          | 'CHIP'         | ''          | ''   | '20160425'  
 '1.5UH/4A'                     | 'SMLF'     | 'EMPTY'  | 'DC-1540M000'(!)           = ''              | ''                 | 'DC-1540M000'              |'L_PCMB042T'| 'NA'                           | 'IO'       | 'CHOKE 1.5UH +-20% 4A(PCMB042T-1R5MS)'          | 'CHIP'         | ''          | ''   | '20160425'  
 'BLM31PG500SN1L/3A'            | 'SMLF'     | 'IND'    | 'CX1PG500007'(!)           = ''              | ''                 | 'CX1PG500007'              |'L1206'| 'BLM31PG500SN1L/3A'            | 'DISCRETE' | 'EMI FILTER CHIP BLM31PG500SN1L(50.3A)EP'       | 'CHIP'         | ''          | ''   | '20160427'  
 'BLM31PG500SN1L/3A'            | 'SMLF'     | 'EMPTY'  | 'CX1PG500007'(!)           = ''              | ''                 | 'CX1PG500007'              |'L1206'| 'NA'                           | 'IO'       | 'EMI FILTER CHIP BLM31PG500SN1L(50.3A)EP'       | 'CHIP'         | ''          | ''   | '20160427'  
 '400NH/17.5A'                  | 'SMLF'     | 'IND'    | 'CV+40H5KZ00'(!)           = ''              | ''                 | 'CV+40H5KZ00'              |'L_HCUVE966490D-121'| '400NH/17.5A'                  | 'DISCRETE' | 'IND SMD 400NH 10% 17.5A(HCUVE966490D-401'      | 'CHIP'         | ''          | ''   | '20160512'  
 '400NH/17.5A'                  | 'SMLF'     | 'EMPTY'  | 'CV+40H5KZ00'(!)           = ''              | ''                 | 'CV+40H5KZ00'              |'L_HCUVE966490D-121'| 'NA'                           | 'IO'       | 'IND SMD 400NH 10% 17.5A(HCUVE966490D-401'      | 'CHIP'         | ''          | ''   | '20160512'  
 '3.3UH/15A'                    | 'SMLF'     | 'IND'    | 'CV-33F0MZ00'(!)           = ''              | ''                 | 'CV-33F0MZ00'              |'L_MAC-12EZ_13-2X12-9'| '3.3UH/15A'                    | 'DISCRETE' | 'IND SMD 3.3UH 20% 15A(MAC-12EZ-3R3M)AEC'       | 'CHIP'         | ''          | ''   | '20160516'  
 '3.3UH/15A'                    | 'SMLF'     | 'EMPTY'  | 'CV-33F0MZ00'(!)           = ''              | ''                 | 'CV-33F0MZ00'              |'L_MAC-12EZ_13-2X12-9'| 'NA'                           | 'IO'       | 'IND SMD 3.3UH 20% 15A(MAC-12EZ-3R3M)AEC'       | 'CHIP'         | ''          | ''   | '20160516'  
 '0.82UH/31A'                   | 'SMLF'     | 'IND'    | 'CV+82W0MZ02'(!)           = ''              | ''                 | 'CV+82W0MZ02'              |'L_MAC-12EZ_13-2X12-9'| '0.82UH/31A'                   | 'DISCRETE' | 'IND SMD 0.82UH 20% 31A(MAC-12EZ-R82M)AEC'      | 'CHIP'         | ''          | ''   | '20160516'  
 '0.82UH/31A'                   | 'SMLF'     | 'EMPTY'  | 'CV+82W0MZ02'(!)           = ''              | ''                 | 'CV+82W0MZ02'              |'L_MAC-12EZ_13-2X12-9'| 'NA'                           | 'IO'       | 'IND SMD 0.82UH 20% 31A(MAC-12EZ-R82M)AEC'      | 'CHIP'         | ''          | ''   | '20160516'  
 '3.3UH/10A'                    | 'SMLF'     | 'IND'    | 'CV-33A0MZ03'(!)           = ''              | ''                 | 'CV-33A0MZ03'              |'L_MAC-10DZ_11-5X10'| '3.3UH/10A'                    | 'DISCRETE' | 'IND SMD 3.3UH 20% 10A(MAC-10DZ-3R3M)AEC'       | 'CHIP'         | ''          | ''   | '20160516'  
 '3.3UH/10A'                    | 'SMLF'     | 'EMPTY'  | 'CV-33A0MZ03'(!)           = ''              | ''                 | 'CV-33A0MZ03'              |'L_MAC-10DZ_11-5X10'| 'NA'                           | 'IO'       | 'IND SMD 3.3UH 20% 10A(MAC-10DZ-3R3M)AEC'       | 'CHIP'         | ''          | ''   | '20160516'  
 'MLB-201209-0330P-N2/1.5A'     | 'SMLF'     | 'IND'    | 'CX00330P000'(!)           = 'End of Design' | 'Comp-Approve'     | 'CX00330P000'              |'L0805'| 'MLB-201209-0330P-N2/1.5A'     | 'DISCRETE' | 'FILTER MLB-201209-0330P-N2 (330,1.5A)'         | 'CHIP'         | ''          | ''   | '20160513'  
 'MLB-201209-0330P-N2/1.5A'     | 'SMLF'     | 'EMPTY'  | 'CX00330P000'(!)           = 'End of Design' | 'Comp-Approve'     | 'CX00330P000'              |'L0805'| 'NA'                           | 'IO'       | 'FILTER MLB-201209-0330P-N2 (330,1.5A)'         | 'CHIP'         | ''          | ''   | '20160513'  
 '90NH/150A'                    | 'SMLF'     | 'IND'    | 'CVA90^0KZ00'(!)           = ''              | 'End of Life'      | 'CVA90^0KZ00'              |'L_HCUVE966490D-121_EOL'| '90NH/150A'                    | 'DISCRETE' | 'IND SMD 90NH 10% 150A(HCUVE966490D-900)'       | 'CHIP'         | ''          | ''   | '20160520'  
 '90NH/150A'                    | 'SMLF'     | 'EMPTY'  | 'CVA90^0KZ00'(!)           = ''              | 'End of Life'      | 'CVA90^0KZ00'              |'L_HCUVE966490D-121_EOL'| 'NA'                           | 'IO'       | 'IND SMD 90NH 10% 150A(HCUVE966490D-900)'       | 'CHIP'         | ''          | ''   | '20160520'  
 '2.2UH/970MA'                  | 'SMLF'     | 'IND'    | 'CV-2210TN00'(!)           = 'End of Design' | 'Comp-Approve'     | 'CV-2210TN00'              |'L1210XB'| '2.2UH/970MA'                  | 'DISCRETE' | 'IND CHIP 2.2UH 30% 970MA(LQH32PZ2R2NN0L)'      | 'CHIP'         | ''          | ''   | '20160526'  
 '2.2UH/970MA'                  | 'SMLF'     | 'EMPTY'  | 'CV-2210TN00'(!)           = 'End of Design' | 'Comp-Approve'     | 'CV-2210TN00'              |'L1210XB'| 'NA'                           | 'IO'       | 'IND CHIP 2.2UH 30% 970MA(LQH32PZ2R2NN0L)'      | 'CHIP'         | ''          | ''   | '20160526'  
 '0.47UH/38A'                   | 'SMLF'     | 'IND'    | 'CV+47^0MZ12'(!)           = ''              | ''                 | 'CV+47^0MZ12'              |'L_CMMS136E_13-45X12-6'| '0.47UH/38A'                   | 'DISCRETE' | 'IND SMD 0.47UH +-20% 38A(CMMS136E-R47MS)'      | 'CHIP'         | ''          | ''   | '20160613'  
 '0.47UH/38A'                   | 'SMLF'     | 'EMPTY'  | 'CV+47^0MZ12'(!)           = ''              | ''                 | 'CV+47^0MZ12'              |'L_CMMS136E_13-45X12-6'| 'NA'                           | 'IO'       | 'IND SMD 0.47UH +-20% 38A(CMMS136E-R47MS)'      | 'CHIP'         | ''          | ''   | '20160613'  
 '0.56UH/31A'                   | 'SMLF'     | 'IND'    | 'CV+56W0MZ01'(!)           = ''              | ''                 | 'CV+56W0MZ01'              |'L_VCMT104T-R56MN5'| '0.56UH/31A'                   | 'DISCRETE' | 'INDSMD 0.56U 20% 31A(VCMT104T-R56MN5)AEC'      | 'CHIP'         | ''          | ''   | '20160614'  
 '0.56UH/31A'                   | 'SMLF'     | 'EMPTY'  | 'CV+56W0MZ01'(!)           = ''              | ''                 | 'CV+56W0MZ01'              |'L_VCMT104T-R56MN5'| 'NA'                           | 'IO'       | 'INDSMD 0.56U 20% 31A(VCMT104T-R56MN5)AEC'      | 'CHIP'         | ''          | ''   | '20160614'  
 '2UH/16A'                      | 'SMLF'     | 'IND'    | 'CV-20G0MZ00'(!)           = ''              | ''                 | 'CV-20G0MZ00'              |'L_VCMT104T-R56MN5'| '2UH/16A'                      | 'DISCRETE' | 'IND SMD 2UH 20% 16A(VCMT104T-2R0MN5)AEC'       | 'CHIP'         | ''          | ''   | '20160614'  
 '2UH/16A'                      | 'SMLF'     | 'EMPTY'  | 'CV-20G0MZ00'(!)           = ''              | ''                 | 'CV-20G0MZ00'              |'L_VCMT104T-R56MN5'| 'NA'                           | 'IO'       | 'IND SMD 2UH 20% 16A(VCMT104T-2R0MN5)AEC'       | 'CHIP'         | ''          | ''   | '20160614'  
 '3.3UH/11A'                    | 'SMLF'     | 'IND'    | 'CV-33B0MZ02'(!)           = ''              | ''                 | 'CV-33B0MZ02'              |'L_VCMT104T-R56MN5'| '3.3UH/11A'                    | 'DISCRETE' | 'IND SMD 3.3U 20% 11A(VCMT104T-3R3MN5)AEC'      | 'CHIP'         | ''          | ''   | '20160614'  
 '3.3UH/11A'                    | 'SMLF'     | 'EMPTY'  | 'CV-33B0MZ02'(!)           = ''              | ''                 | 'CV-33B0MZ02'              |'L_VCMT104T-R56MN5'| 'NA'                           | 'IO'       | 'IND SMD 3.3U 20% 11A(VCMT104T-3R3MN5)AEC'      | 'CHIP'         | ''          | ''   | '20160614'  
 '2.2UH/9A'                     | 'SMLF'     | 'IND'    | 'CV-2290MZ02'(!)           = ''              | ''                 | 'CV-2290MZ02'              |'L_VCMT063T-2R2MN5'| '2.2UH/9A'                     | 'DISCRETE' | 'IND SMD 2.2UH 20% 9A(VCMT063T-2R2MN5)AEC'      | 'CHIP'         | ''          | ''   | '20160614'  
 '2.2UH/9A'                     | 'SMLF'     | 'EMPTY'  | 'CV-2290MZ02'(!)           = ''              | ''                 | 'CV-2290MZ02'              |'L_VCMT063T-2R2MN5'| 'NA'                           | 'IO'       | 'IND SMD 2.2UH 20% 9A(VCMT063T-2R2MN5)AEC'      | 'CHIP'         | ''          | ''   | '20160614'  
 '6.8UH/5.5A'                   | 'SMLF'     | 'IND'    | 'CV-6855MZ01'(!)           = ''              | ''                 | 'CV-6855MZ01'              |'L_VCMT063T-2R2MN5'| '6.8UH/5.5A'                   | 'DISCRETE' | 'INDSMD 6.8U 20% 5.5A(VCMT063T-6R8MN5)AEC'      | 'CHIP'         | ''          | ''   | '20160614'  
 '6.8UH/5.5A'                   | 'SMLF'     | 'EMPTY'  | 'CV-6855MZ01'(!)           = ''              | ''                 | 'CV-6855MZ01'              |'L_VCMT063T-2R2MN5'| 'NA'                           | 'IO'       | 'INDSMD 6.8U 20% 5.5A(VCMT063T-6R8MN5)AEC'      | 'CHIP'         | ''          | ''   | '20160614'  
 '600NH/26A'                    | 'SMLF'     | 'IND'    | 'CV+60R0KZ00'(!)           = 'End of Design' | 'Comp-Approve'     | 'CV+60R0KZ00'              |'L_HCUVD8095D-102KBQL_8X8'| '600NH/26A'                    | 'DISCRETE' | 'IND SMD 600NH +-10% 26A(HCUVD8095D-601K)'      | 'CHIP'         | ''          | ''   | '20160617'  
 '600NH/26A'                    | 'SMLF'     | 'EMPTY'  | 'CV+60R0KZ00'(!)           = 'End of Design' | 'Comp-Approve'     | 'CV+60R0KZ00'              |'L_HCUVD8095D-102KBQL_8X8'| 'NA'                           | 'IO'       | 'IND SMD 600NH +-10% 26A(HCUVD8095D-601K)'      | 'CHIP'         | ''          | ''   | '20160617'  
 '90NH/134A'                    | 'SMLF'     | 'IND'    | 'CVA90^0KZ01'(!)           = ''              | ''                 | 'CVA90^0KZ01'              |'L_SLA3735B'| '90NH/134A'                    | 'DISCRETE' | 'IND SMD 90NH +-10% 134A(SLA3735B-90K)'         | 'CHIP'         | ''          | ''   | '20160628'  
 '90NH/134A'                    | 'SMLF'     | 'EMPTY'  | 'CVA90^0KZ01'(!)           = ''              | ''                 | 'CVA90^0KZ01'              |'L_SLA3735B'| 'NA'                           | 'IO'       | 'IND SMD 90NH +-10% 134A(SLA3735B-90K)'         | 'CHIP'         | ''          | ''   | '20160628'  
 '180NH/60A'                    | 'SMLF'     | 'IND'    | 'CV+18^0KZ06'(!)           = 'End of Design' | 'Comp-Approve'     | 'CV+18^0KZ06'              |'L_HCUVE966490D-121'| '180NH/60A'                    | 'DISCRETE' | 'IND SMD 180NH 10% 60A(HCUVE966490D-181) '      | 'CHIP'         | ''          | ''   | '20160721'  
 '180NH/60A'                    | 'SMLF'     | 'EMPTY'  | 'CV+18^0KZ06'(!)           = 'End of Design' | 'Comp-Approve'     | 'CV+18^0KZ06'              |'L_HCUVE966490D-121'| 'NA'                           | 'IO'       | 'IND SMD 180NH 10% 60A(HCUVE966490D-181) '      | 'CHIP'         | ''          | ''   | '20160721'  
 'BLM18AG601SH1D/200MA'         | 'SMLF'     | 'IND'    | 'CX8AG601000'(!)           = ''              | ''                 | 'CX8AG601000'              |'L0603'| 'BLM18AG601SH1D/200MA'         | 'DISCRETE' | 'EMI FILTER BLM18AG601SH1D(600,200MA)'          | 'CHIP'         | ''          | ''   | '20160804'  
 'BLM18AG601SH1D/200MA'         | 'SMLF'     | 'EMPTY'  | 'CX8AG601000'(!)           = ''              | ''                 | 'CX8AG601000'              |'L0603'| 'NA'                           | 'IO'       | 'EMI FILTER BLM18AG601SH1D(600,200MA)'          | 'CHIP'         | ''          | ''   | '20160804'  
 '1UH/62A'                      | 'SMLF'     | 'IND'    | 'CV-10^0MZ11'(!)           = ''              | ''                 | 'CV-10^0MZ11'              |'L_MSE-12HZN1R0M-M1Q'| '1UH/62A'                      | 'DISCRETE' | 'IND SMD 1UH 20% 62A(MSE-12HZN1R0M-M1Q)'        | 'CHIP'         | ''          | ''   | '20160805'  
 '1UH/62A'                      | 'SMLF'     | 'EMPTY'  | 'CV-10^0MZ11'(!)           = ''              | ''                 | 'CV-10^0MZ11'              |'L_MSE-12HZN1R0M-M1Q'| 'NA'                           | 'IO'       | 'IND SMD 1UH 20% 62A(MSE-12HZN1R0M-M1Q)'        | 'CHIP'         | ''          | ''   | '20160805'  
 '1.5UH/53A'                    | 'SMLF'     | 'IND'    | 'CV-15^0MZ01'(!)           = ''              | ''                 | 'CV-15^0MZ01'              |'L_MSE-12HZN1R0M-M1Q'| '1.5UH/53A'                    | 'DISCRETE' | 'IND SMD 1.5UH 20% 53A(MSE-12HZN1R5M-M1Q)'      | 'CHIP'         | ''          | ''   | '20160805'  
 '1.5UH/53A'                    | 'SMLF'     | 'EMPTY'  | 'CV-15^0MZ01'(!)           = ''              | ''                 | 'CV-15^0MZ01'              |'L_MSE-12HZN1R0M-M1Q'| 'NA'                           | 'IO'       | 'IND SMD 1.5UH 20% 53A(MSE-12HZN1R5M-M1Q)'      | 'CHIP'         | ''          | ''   | '20160805'  
 '2.2UH/50A'                    | 'SMLF'     | 'IND'    | 'CV-22^0MZ06'(!)           = ''              | ''                 | 'CV-22^0MZ06'              |'L_MSE-12HZN1R0M-M1Q'| '2.2UH/50A'                    | 'DISCRETE' | 'IND SMD 2.2UH 20% 50A(MSE-12HZN2R2M-M1Q)'      | 'CHIP'         | ''          | ''   | '20160805'  
 '2.2UH/50A'                    | 'SMLF'     | 'EMPTY'  | 'CV-22^0MZ06'(!)           = ''              | ''                 | 'CV-22^0MZ06'              |'L_MSE-12HZN1R0M-M1Q'| 'NA'                           | 'IO'       | 'IND SMD 2.2UH 20% 50A(MSE-12HZN2R2M-M1Q)'      | 'CHIP'         | ''          | ''   | '20160805'  
 '3.3UH/45A'                    | 'SMLF'     | 'IND'    | 'CV-33^0MZ01'(!)           = ''              | ''                 | 'CV-33^0MZ01'              |'L_MSE-12HZN1R0M-M1Q'| '3.3UH/45A'                    | 'DISCRETE' | 'IND SMD 3.3UH 20% 45A(MSE-12HZN3R3M-M1Q)'      | 'CHIP'         | ''          | ''   | '20160805'  
 '3.3UH/45A'                    | 'SMLF'     | 'EMPTY'  | 'CV-33^0MZ01'(!)           = ''              | ''                 | 'CV-33^0MZ01'              |'L_MSE-12HZN1R0M-M1Q'| 'NA'                           | 'IO'       | 'IND SMD 3.3UH 20% 45A(MSE-12HZN3R3M-M1Q)'      | 'CHIP'         | ''          | ''   | '20160805'  
 '4.7UH/35A'                    | 'SMLF'     | 'IND'    | 'CV-47^0MZ00'(!)           = ''              | ''                 | 'CV-47^0MZ00'              |'L_MSE-12HZN1R0M-M1Q'| '4.7UH/35A'                    | 'DISCRETE' | 'IND SMD 4.7UH 20% 35A(MSE-12HZN4R7M-M1Q)'      | 'CHIP'         | ''          | ''   | '20160805'  
 '4.7UH/35A'                    | 'SMLF'     | 'EMPTY'  | 'CV-47^0MZ00'(!)           = ''              | ''                 | 'CV-47^0MZ00'              |'L_MSE-12HZN1R0M-M1Q'| 'NA'                           | 'IO'       | 'IND SMD 4.7UH 20% 35A(MSE-12HZN4R7M-M1Q)'      | 'CHIP'         | ''          | ''   | '20160805'  
 '1UH/19A'                      | 'SMLF'     | 'IND'    | 'CV-10J0KZ01'(!)           = ''              | ''                 | 'CV-10J0KZ01'              |'L_HCUVD8095D-102KBQL_8X8'| '1UH/19A'                      | 'DISCRETE' | 'IND SMD 1UH 10% 19A(HCUVD8095-102KQL)'         | 'CHIP'         | ''          | ''   | '20160817'  
 '1UH/19A'                      | 'SMLF'     | 'EMPTY'  | 'CV-10J0KZ01'(!)           = ''              | ''                 | 'CV-10J0KZ01'              |'L_HCUVD8095D-102KBQL_8X8'| 'NA'                           | 'IO'       | 'IND SMD 1UH 10% 19A(HCUVD8095-102KQL)'         | 'CHIP'         | ''          | ''   | '20160817'  
 '0.6UH/20A'                    | 'SMLF'     | 'IND'    | 'CV+60K0KZ01'(!)           = ''              | ''                 | 'CV+60K0KZ01'              |'L_HCUVD6595D-601KLY_6-5X6-5'| '0.6UH/20A'                    | 'DISCRETE' | 'IND SMD 0.6UH 10% 20A(HCUVD6595-601KLY)'       | 'CHIP'         | ''          | ''   | '20160817'  
 '0.6UH/20A'                    | 'SMLF'     | 'EMPTY'  | 'CV+60K0KZ01'(!)           = ''              | ''                 | 'CV+60K0KZ01'              |'L_HCUVD6595D-601KLY_6-5X6-5'| 'NA'                           | 'IO'       | 'IND SMD 0.6UH 10% 20A(HCUVD6595-601KLY)'       | 'CHIP'         | ''          | ''   | '20160817'  
 '1UH/12A'                      | 'SMLF'     | 'IND'    | 'CV-10C0KZ01'(!)           = ''              | 'End of Life'      | 'CV-10C0KZ01'              |'L_HCUVD6595D-601KLY_6-5X6-5_EOL'| '1UH/12A'                      | 'DISCRETE' | 'IND SMD 1UH 10% 12A(HCUVD6595-102KLY)'         | 'CHIP'         | ''          | ''   | '20160817'  
 '1UH/12A'                      | 'SMLF'     | 'EMPTY'  | 'CV-10C0KZ01'(!)           = ''              | 'End of Life'      | 'CV-10C0KZ01'              |'L_HCUVD6595D-601KLY_6-5X6-5_EOL'| 'NA'                           | 'IO'       | 'IND SMD 1UH 10% 12A(HCUVD6595-102KLY)'         | 'CHIP'         | ''          | ''   | '20160817'  
 'BLM15AG121SN1D/500MA'         | 'SMLF'     | 'IND'    | 'CX5AG121002'(!)           = ''              | ''                 | 'CX5AG121002'              |'L0402'| 'BLM15AG121SN1D/500MA'         | 'DISCRETE' | 'EMI FILTER BLM15AG121SN1D(120,500MA)'          | 'CHIP'         | ''          | ''   | '20141027'  
 'BLM15AG121SN1D/500MA'         | 'SMLF'     | 'EMPTY'  | 'CX5AG121002'(!)           = ''              | ''                 | 'CX5AG121002'              |'L0402'| 'NA'                           | 'IO'       | 'EMI FILTER BLM15AG121SN1D(120,500MA)'          | 'CHIP'         | ''          | ''   | '20141027'  
 '180NH/60A'                    | 'SMLF'     | 'IND'    | 'CV+18^0KZ05'(!)           = ''              | ''                 | 'CV+18^0KZ05'              |'L_HCUVE117583D_10-7X7-5'| '180NH/60A'                    | 'DISCRETE' | 'IND SMD 180NH 10% 60A(HCUVE117583D-181)'       | 'CHIP'         | ''          | ''   | '20160914'  
 '180NH/60A'                    | 'SMLF'     | 'EMPTY'  | 'CV+18^0KZ05'(!)           = ''              | ''                 | 'CV+18^0KZ05'              |'L_HCUVE117583D_10-7X7-5'| 'NA'                           | 'IO'       | 'IND SMD 180NH 10% 60A(HCUVE117583D-181)'       | 'CHIP'         | ''          | ''   | '20160914'  
 '320NH/34A'                    | 'SMLF'     | 'IND'    | 'CV+32Z0KZ00'(!)           = ''              | ''                 | 'CV+32Z0KZ00'              |'L_HCUVE117583D_10-7X7-5'| '320NH/34A'                    | 'DISCRETE' | 'IND SMD 320NH 10% 34A(HCUVE117583D-321)'       | 'CHIP'         | ''          | ''   | '20160914'  
 '320NH/34A'                    | 'SMLF'     | 'EMPTY'  | 'CV+32Z0KZ00'(!)           = ''              | ''                 | 'CV+32Z0KZ00'              |'L_HCUVE117583D_10-7X7-5'| 'NA'                           | 'IO'       | 'IND SMD 320NH 10% 34A(HCUVE117583D-321)'       | 'CHIP'         | ''          | ''   | '20160914'  
 '150NH/72A'                    | 'SMLF'     | 'IND'    | 'CV+15^0KZ11'(!)           = ''              | ''                 | 'CV+15^0KZ11'              |'L_HCUVE117583D_10-7X7-5'| '150NH/72A'                    | 'DISCRETE' | 'IND SMD 150NH 10% 72A(HCUVE117583D-151)'       | 'CHIP'         | ''          | ''   | '20160914'  
 '150NH/72A'                    | 'SMLF'     | 'EMPTY'  | 'CV+15^0KZ11'(!)           = ''              | ''                 | 'CV+15^0KZ11'              |'L_HCUVE117583D_10-7X7-5'| 'NA'                           | 'IO'       | 'IND SMD 150NH 10% 72A(HCUVE117583D-151)'       | 'CHIP'         | ''          | ''   | '20160914'  
 '120NH/90A'                    | 'SMLF'     | 'IND'    | 'CV+12^0KZ08'(!)           = ''              | ''                 | 'CV+12^0KZ08'              |'L_HCUVE117583D_10-7X7-5'| '120NH/90A'                    | 'DISCRETE' | 'IND SMD 120NH 10% 90A(HCUVE117583D-121)'       | 'CHIP'         | ''          | ''   | '20160914'  
 '120NH/90A'                    | 'SMLF'     | 'EMPTY'  | 'CV+12^0KZ08'(!)           = ''              | ''                 | 'CV+12^0KZ08'              |'L_HCUVE117583D_10-7X7-5'| 'NA'                           | 'IO'       | 'IND SMD 120NH 10% 90A(HCUVE117583D-121)'       | 'CHIP'         | ''          | ''   | '20160914'  
 'BLM21PG331SN1D'               | 'SMLF'     | 'IND'    | 'CX1PG331003'(!)           = ''              | 'End of Life'      | 'CX1PG331003'              |'L0805_EOL'| 'BLM21PG331SN1D'               | 'DISCRETE' | 'EMI FIL CHIP BLM21PG331SN1D(330,1.5A)'         | 'CHIP'         | ''          | ''   | '20111011'  
 'BLM21PG331SN1D'               | 'SMLF'     | 'EMPTY'  | 'CX1PG331003'(!)           = ''              | 'End of Life'      | 'CX1PG331003'              |'L0805_EOL'| 'NA'                           | 'IO'       | 'EMI FIL CHIP BLM21PG331SN1D(330,1.5A)'         | 'CHIP'         | ''          | ''   | '20111011'  
 '600/0.5A'                     | 'SMLF'     | 'IND'    | 'CX8EG601000'(!)           = ''              | ''                 | 'CX8EG601000'              |'L0603'| '600/0.5A'                     | 'DISCRETE' | 'EMI FILTER BLM18EG601SN1D(600,0.5A)'           | 'CHIP'         | ''          | ''   | '20161004'  
 '600/0.5A'                     | 'SMLF'     | 'EMPTY'  | 'CX8EG601000'(!)           = ''              | ''                 | 'CX8EG601000'              |'L0603'| 'NA'                           | 'IO'       | 'EMI FILTER BLM18EG601SN1D(600,0.5A)'           | 'CHIP'         | ''          | ''   | '20161004'  
 '60NH/66A'                     | 'SMLF'     | 'IND'    | 'CVA60^0KZ00'(!)           = ''              | ''                 | 'CVA60^0KZ00'              |'L_HCUVE966490D-121'| '60NH/66A'                     | 'DISCRETE' | 'IND SMD 60NH 10% 66A(HCUVE966490-600)'         | 'CHIP'         | ''          | ''   | '20161005'  
 '60NH/66A'                     | 'SMLF'     | 'EMPTY'  | 'CVA60^0KZ00'(!)           = ''              | ''                 | 'CVA60^0KZ00'              |'L_HCUVE966490D-121'| 'NA'                           | 'IO'       | 'IND SMD 60NH 10% 66A(HCUVE966490-600)'         | 'CHIP'         | ''          | ''   | '20161005'  
 '0.36UH/30A'                   | 'SMLF'     | 'IND'    | 'CV+3630MZ01'(!)           = ''              | ''                 | 'CV+3630MZ01'              |'L_MPC1055'| '0.36UH/30A'                   | 'DISCRETE' | 'IND SMD 0.36UH 20% 30A(MPC1055LR36) EU'        | 'CHIP'         | ''          | ''   | '20161006'  
 '0.36UH/30A'                   | 'SMLF'     | 'EMPTY'  | 'CV+3630MZ01'(!)           = ''              | ''                 | 'CV+3630MZ01'              |'L_MPC1055'| 'NA'                           | 'IO'       | 'IND SMD 0.36UH 20% 30A(MPC1055LR36) EU'        | 'CHIP'         | ''          | ''   | '20161006'  
 'HCB2012KF-300T60/6A'          | 'SMLF'     | 'IND'    | 'CX300T60000'(!)           = ''              | ''                 | 'CX300T60000'              |'L0805'| 'HCB2012KF-300T60/6A'          | 'DISCRETE' | 'EMI FILTER HCB2012KF-300T60(30,6A)'            | 'CHIP'         | ''          | ''   | '20161018'  
 'HCB2012KF-300T60/6A'          | 'SMLF'     | 'EMPTY'  | 'CX300T60000'(!)           = ''              | ''                 | 'CX300T60000'              |'L0805'| 'NA'                           | 'IO'       | 'EMI FILTER HCB2012KF-300T60(30,6A)'            | 'CHIP'         | ''          | ''   | '20161018'  
 '1.5UH/20.9A'                  | 'SMLF'     | 'IND'    | 'CV-15L0MZ00'(!)           = ''              | ''                 | 'CV-15L0MZ00'              |'L_VCMI136E-1R5MN54_13-45X12-6'| '1.5UH/20.9A'                  | 'DISCRETE' | 'IND SMD 1.5U 20% 20.9A(VCMI136E-1R5MN54)'      | 'CHIP'         | ''          | ''   | '20161024'  
 '1.5UH/20.9A'                  | 'SMLF'     | 'EMPTY'  | 'CV-15L0MZ00'(!)           = ''              | ''                 | 'CV-15L0MZ00'              |'L_VCMI136E-1R5MN54_13-45X12-6'| 'NA'                           | 'IO'       | 'IND SMD 1.5U 20% 20.9A(VCMI136E-1R5MN54)'      | 'CHIP'         | ''          | ''   | '20161024'  
 '0.36UH/30A'                   | 'SMLF'     | 'IND'    | 'CV+36V0MZ13'(!)           = ''              | ''                 | 'CV+36V0MZ13'              |'L_PCMB104TXA'| '0.36UH/30A'                   | 'DISCRETE' | 'IND SMD 0.36UH +-20% 30A(PCMB104T-R36MT)'      | 'CHIP'         | ''          | ''   | '20161026'  
 '0.36UH/30A'                   | 'SMLF'     | 'EMPTY'  | 'CV+36V0MZ13'(!)           = ''              | ''                 | 'CV+36V0MZ13'              |'L_PCMB104TXA'| 'NA'                           | 'IO'       | 'IND SMD 0.36UH +-20% 30A(PCMB104T-R36MT)'      | 'CHIP'         | ''          | ''   | '20161026'  
 'BLM03AX601SN1D'               | 'SMLF'     | 'IND'    | 'CX3AX601000'(!)           = ''              | ''                 | 'CX3AX601000'              |'L0201'| 'BLM03AX601SN1D'               | 'DISCRETE' | 'EMI FILTER BEAD BLM03AX601SN(600,250MA)'       | 'CHIP'         | ''          | ''   | '20161102'  
 'BLM03AX601SN1D'               | 'SMLF'     | 'EMPTY'  | 'CX3AX601000'(!)           = ''              | ''                 | 'CX3AX601000'              |'L0201'| 'NA'                           | 'IO'       | 'EMI FILTER BEAD BLM03AX601SN(600,250MA)'       | 'CHIP'         | ''          | ''   | '20161102'  
 '400NH/27A'                    | 'SMLF'     | 'IND'    | 'CV+40S0KZ01'(!)           = 'End of Design' | 'P/N Release'      | 'CV+40S0KZ01'              |'L_HCUVE966412D-221'| '400NH/27A'                    | 'DISCRETE' | 'IND SMD 400NH 10% 27A(HCUVE966412D-401)'       | 'CHIP'         | ''          | ''   | '20161104'  
 '400NH/27A'                    | 'SMLF'     | 'EMPTY'  | 'CV+40S0KZ01'(!)           = 'End of Design' | 'P/N Release'      | 'CV+40S0KZ01'              |'L_HCUVE966412D-221'| 'NA'                           | 'IO'       | 'IND SMD 400NH 10% 27A(HCUVE966412D-401)'       | 'CHIP'         | ''          | ''   | '20161104'  
 '470NH/23A'                    | 'SMLF'     | 'IND'    | 'CV+47N0KZ00'(!)           = 'End of Design' | 'Comp-Approve'     | 'CV+47N0KZ00'              |'L_HCUVE966412D-221'| '470NH/23A'                    | 'DISCRETE' | 'IND SMD 470NH 10% 23A(HCUVE966412D-471)'       | 'CHIP'         | ''          | ''   | '20161104'  
 '470NH/23A'                    | 'SMLF'     | 'EMPTY'  | 'CV+47N0KZ00'(!)           = 'End of Design' | 'Comp-Approve'     | 'CV+47N0KZ00'              |'L_HCUVE966412D-221'| 'NA'                           | 'IO'       | 'IND SMD 470NH 10% 23A(HCUVE966412D-471)'       | 'CHIP'         | ''          | ''   | '20161104'  
 '0.68UH/3.4A'                  | 'SMLF'     | 'IND'    | 'CV+6834MZ00'(!)           = ''              | ''                 | 'CV+6834MZ00'              |'L0806XB'| '0.68UH/3.4A'                  | 'DISCRETE' | 'IND SMD 0.68UH 20% 3.4A(LQM2MPNR68MGH)'        | 'CHIP'         | ''          | ''   | '20161109'  
 '0.68UH/3.4A'                  | 'SMLF'     | 'EMPTY'  | 'CV+6834MZ00'(!)           = ''              | ''                 | 'CV+6834MZ00'              |'L0806XB'| 'NA'                           | 'IO'       | 'IND SMD 0.68UH 20% 3.4A(LQM2MPNR68MGH)'        | 'CHIP'         | ''          | ''   | '20161109'  
 '300NH/37A'                    | 'SMLF'     | 'IND'    | 'CV+30^0KZ08'(!)           = 'End of Design' | 'Comp-Approve'     | 'CV+30^0KZ08'              |'L_HCUVE966412D-221'| '300NH/37A'                    | 'DISCRETE' | 'IND SMD 300NH 10% 37A(HCUVE966412D-301)'       | 'CHIP'         | ''          | ''   | '20161109'  
 '300NH/37A'                    | 'SMLF'     | 'EMPTY'  | 'CV+30^0KZ08'(!)           = 'End of Design' | 'Comp-Approve'     | 'CV+30^0KZ08'              |'L_HCUVE966412D-221'| 'NA'                           | 'IO'       | 'IND SMD 300NH 10% 37A(HCUVE966412D-301)'       | 'CHIP'         | ''          | ''   | '20161109'  
 '400NH/45A'                    | 'SMLF'     | 'IND'    | 'CV+40^0EZ01'(!)           = ''              | ''                 | 'CV+40^0EZ01'              |'L_HCUV117595'| '400NH/45A'                    | 'DISCRETE' | 'IND SMD 400NH +-15% 45A(HCUV117595-401)'       | 'CHIP'         | ''          | ''   | '20161112'  
 '400NH/45A'                    | 'SMLF'     | 'EMPTY'  | 'CV+40^0EZ01'(!)           = ''              | ''                 | 'CV+40^0EZ01'              |'L_HCUV117595'| 'NA'                           | 'IO'       | 'IND SMD 400NH +-15% 45A(HCUV117595-401)'       | 'CHIP'         | ''          | ''   | '20161112'  
 '800NH/19A'                    | 'SMLF'     | 'IND'    | 'CV+80J0KZ00'(!)           = 'End of Design' | 'Comp-Approve'     | 'CV+80J0KZ00'              |'L_HCUVD8095D-102KBQL_8X8'| '800NH/19A'                    | 'DISCRETE' | 'IND SMD 800NH 10% 19A(HCUVD8095D-801KBQL'      | 'CHIP'         | ''          | ''   | '20161116'  
 '800NH/19A'                    | 'SMLF'     | 'EMPTY'  | 'CV+80J0KZ00'(!)           = 'End of Design' | 'Comp-Approve'     | 'CV+80J0KZ00'              |'L_HCUVD8095D-102KBQL_8X8'| 'NA'                           | 'IO'       | 'IND SMD 800NH 10% 19A(HCUVD8095D-801KBQL'      | 'CHIP'         | ''          | ''   | '20161116'  
 '300NH/38A'                    | 'SMLF'     | 'IND'    | 'CV+30^0KZ09'(!)           = ''              | ''                 | 'CV+30^0KZ09'              |'L_HCUV117595'| '300NH/38A'                    | 'DISCRETE' | 'IND SMD 300NH 10% 38A(HCUV117595-301B)'        | 'CHIP'         | ''          | ''   | '20161116'  
 '300NH/38A'                    | 'SMLF'     | 'EMPTY'  | 'CV+30^0KZ09'(!)           = ''              | ''                 | 'CV+30^0KZ09'              |'L_HCUV117595'| 'NA'                           | 'IO'       | 'IND SMD 300NH 10% 38A(HCUV117595-301B)'        | 'CHIP'         | ''          | ''   | '20161116'  
 '320NH/45A'                    | 'SMLF'     | 'IND'    | 'CV+32^0EZ00'(!)           = ''              | ''                 | 'CV+32^0EZ00'              |'L_HCUV117595'| '320NH/45A'                    | 'DISCRETE' | 'IND SMD 320NH +-15% 45A(HCUV117595-321)'       | 'CHIP'         | ''          | ''   | '20161205'  
 '320NH/45A'                    | 'SMLF'     | 'EMPTY'  | 'CV+32^0EZ00'(!)           = ''              | ''                 | 'CV+32^0EZ00'              |'L_HCUV117595'| 'NA'                           | 'IO'       | 'IND SMD 320NH +-15% 45A(HCUV117595-321)'       | 'CHIP'         | ''          | ''   | '20161205'  
 '600NH/26A'                    | 'SMLF'     | 'IND'    | 'CV+60R0KZ01'(!)           = ''              | ''                 | 'CV+60R0KZ01'              |'L_HCUVD8095D-102KBQL_8X8'| '600NH/26A'                    | 'DISCRETE' | 'IND SMD 600NH 10% 26A(HCUVD8095-601K)'         | 'CHIP'         | ''          | ''   | '20161215'  
 '600NH/26A'                    | 'SMLF'     | 'EMPTY'  | 'CV+60R0KZ01'(!)           = ''              | ''                 | 'CV+60R0KZ01'              |'L_HCUVD8095D-102KBQL_8X8'| 'NA'                           | 'IO'       | 'IND SMD 600NH 10% 26A(HCUVD8095-601K)'         | 'CHIP'         | ''          | ''   | '20161215'  
 '2.2UH/5A'                     | 'SMLF'     | 'IND'    | 'CV-2250MZ00'(!)           = ''              | ''                 | 'CV-2250MZ00'              |'L_PCMB051H-2R2MS_5-4X5-2'| '2.2UH/5A'                     | 'DISCRETE' | 'IND SMD 2.2UH +-20% 5A PCMB051H-2R2MS'         | 'CHIP'         | ''          | ''   | '20161220'  
 '2.2UH/5A'                     | 'SMLF'     | 'EMPTY'  | 'CV-2250MZ00'(!)           = ''              | ''                 | 'CV-2250MZ00'              |'L_PCMB051H-2R2MS_5-4X5-2'| 'NA'                           | 'IO'       | 'IND SMD 2.2UH +-20% 5A PCMB051H-2R2MS'         | 'CHIP'         | ''          | ''   | '20161220'  
 'LBR2012T100K/150MA'           | 'SMLF'     | 'IND'    | 'CV01002KZ01'(!)           = ''              | ''                 | 'CV01002KZ01'              |'L0805_H56'| 'LBR2012T100K/150MA'           | 'DISCRETE' | 'IND SMD 10UH 10% 150MA(LBR2012T100K)'          | 'CHIP'         | ''          | ''   | '20170302'  
 'LBR2012T100K/150MA'           | 'SMLF'     | 'EMPTY'  | 'CV01002KZ01'(!)           = ''              | ''                 | 'CV01002KZ01'              |'L0805_H56'| 'NA'                           | 'IO'       | 'IND SMD 10UH 10% 150MA(LBR2012T100K)'          | 'CHIP'         | ''          | ''   | '20170302'  
 '400NH/30A'                    | 'SMLF'     | 'IND'    | 'CV+40V0KZ00'(!)           = ''              | ''                 | 'CV+40V0KZ00'              |'L_HCUVD6595D-601KLY_6-5X6-5'| '400NH/30A'                    | 'DISCRETE' | 'IND SMD 400NH 10% 30A(HCUVD6595-401K)'         | 'CHIP'         | ''          | ''   | '20170309'  
 '400NH/30A'                    | 'SMLF'     | 'EMPTY'  | 'CV+40V0KZ00'(!)           = ''              | ''                 | 'CV+40V0KZ00'              |'L_HCUVD6595D-601KLY_6-5X6-5'| 'NA'                           | 'IO'       | 'IND SMD 400NH 10% 30A(HCUVD6595-401K)'         | 'CHIP'         | ''          | ''   | '20170309'  
 'GMLB-555018-0800P-N1-QU/8A'   | 'SMLF'     | 'IND'    | 'CX555018000'(!)           = ''              | ''                 | 'CX555018000'              |'L_GMLB-555018_5-5X5'| 'GMLB-555018-0800P-N1-QU/8A'   | 'DISCRETE' | 'EMI FILTER GMLB-555018-0800P-N1(800,8A)'       | 'CHIP'         | ''          | ''   | '20170331'  
 'GMLB-555018-0800P-N1-QU/8A'   | 'SMLF'     | 'EMPTY'  | 'CX555018000'(!)           = ''              | ''                 | 'CX555018000'              |'L_GMLB-555018_5-5X5'| 'NA'                           | 'IO'       | 'EMI FILTER GMLB-555018-0800P-N1(800,8A)'       | 'CHIP'         | ''          | ''   | '20170331'  
 '10UH/4.5A'                    | 'SMLF'     | 'IND'    | 'CV01045MZ02'(!)           = ''              | ''                 | 'CV01045MZ02'              |'L_MHCI05030_5-7X5-4'| '10UH/4.5A'                    | 'DISCRETE' | 'IND SMD 10UH 20% 4.5A(MHCI05030-100M-R8)'      | 'CHIP'         | ''          | ''   | '20170421'  
 '10UH/4.5A'                    | 'SMLF'     | 'EMPTY'  | 'CV01045MZ02'(!)           = ''              | ''                 | 'CV01045MZ02'              |'L_MHCI05030_5-7X5-4'| 'NA'                           | 'IO'       | 'IND SMD 10UH 20% 4.5A(MHCI05030-100M-R8)'      | 'CHIP'         | ''          | ''   | '20170421'  
 'MPZ2012S601ATD25/2A'          | 'SMLF'     | 'IND'    | 'TX1ATD25000'(!)           = ''              | ''                 | 'TX1ATD25000'              |'L_MLZ2012'| 'MPZ2012S601ATD25/2A'          | 'DISCRETE' | 'EMI FIL MPZ2012S601ATD25(600,2A)EMS-TEA'       | 'CHIP'         | ''          | ''   | '20170614'  
 'MPZ2012S601ATD25/2A'          | 'SMLF'     | 'EMPTY'  | 'TX1ATD25000'(!)           = ''              | ''                 | 'TX1ATD25000'              |'L_MLZ2012'| 'NA'                           | 'IO'       | 'EMI FIL MPZ2012S601ATD25(600,2A)EMS-TEA'       | 'CHIP'         | ''          | ''   | '20170614'  
 'HI3312X101R-10/10A'           | 'SMLF'     | 'IND'    | 'CX2X101R000'(!)           = ''              | ''                 | 'CX2X101R000'              |'L_HI3312X101R-10_8-5X3-05'| 'HI3312X101R-10/10A'           | 'DISCRETE' | 'EMI FILTER BEAD HI3312X101R-10(100,10A)'       | 'CHIP'         | ''          | ''   | '20170628'  
 'HI3312X101R-10/10A'           | 'SMLF'     | 'EMPTY'  | 'CX2X101R000'(!)           = ''              | ''                 | 'CX2X101R000'              |'L_HI3312X101R-10_8-5X3-05'| 'NA'                           | 'IO'       | 'EMI FILTER BEAD HI3312X101R-10(100,10A)'       | 'CHIP'         | ''          | ''   | '20170628'  
 '300NH/41A'                    | 'SMLF'     | 'IND'    | 'CV+30^0KZ10'(!)           = ''              | ''                 | 'CV+30^0KZ10'              |'L_HCUV117595'| '300NH/41A'                    | 'DISCRETE' | 'IND SMD 300NH 10% 41A(HCUVE117595-301B)'       | 'CHIP'         | ''          | ''   | '20170620'  
 '300NH/41A'                    | 'SMLF'     | 'EMPTY'  | 'CV+30^0KZ10'(!)           = ''              | ''                 | 'CV+30^0KZ10'              |'L_HCUV117595'| 'NA'                           | 'IO'       | 'IND SMD 300NH 10% 41A(HCUVE117595-301B)'       | 'CHIP'         | ''          | ''   | '20170620'  
 '22NH/1.85A'                   | 'SMLF'     | 'IND'    | 'CVA2219KN01'(!)           = 'End of Design' | 'Comp-Approve'     | 'CVA2219KN01'              |'L0805'| '22NH/1.85A'                   | 'DISCRETE' | 'IND CHIP 22NH 10% 1.85A(MLH2012F22NKT)'        | 'CHIP'         | ''          | ''   | '20170731'  
 '22NH/1.85A'                   | 'SMLF'     | 'EMPTY'  | 'CVA2219KN01'(!)           = 'End of Design' | 'Comp-Approve'     | 'CVA2219KN01'              |'L0805'| 'NA'                           | 'IO'       | 'IND CHIP 22NH 10% 1.85A(MLH2012F22NKT)'        | 'CHIP'         | ''          | ''   | '20170731'  
 '22NH/2A'                      | 'SMLF'     | 'IND'    | 'CVA2220KN00'(!)           = ''              | ''                 | 'CVA2220KN00'              |'L0805'| '22NH/2A'                      | 'DISCRETE' | 'IND CHIP 22NH 10% 2A(MPB201209T-22NK-NA2'      | 'CHIP'         | ''          | ''   | '20170731'  
 '22NH/2A'                      | 'SMLF'     | 'EMPTY'  | 'CVA2220KN00'(!)           = ''              | ''                 | 'CVA2220KN00'              |'L0805'| 'NA'                           | 'IO'       | 'IND CHIP 22NH 10% 2A(MPB201209T-22NK-NA2'      | 'CHIP'         | ''          | ''   | '20170731'  
 '100NH/35A'                    | 'SMLF'     | 'IND'    | 'CV+10^0KZ02'(!)           = ''              | ''                 | 'CV+10^0KZ02'              |'L_HCB7650-101_7-6X7-5'| '100NH/35A'                    | 'DISCRETE' | 'IND SMD 100NH 10% 35A(HCB7650-101)'            | 'CHIP'         | ''          | ''   | '20170830'  
 '100NH/35A'                    | 'SMLF'     | 'EMPTY'  | 'CV+10^0KZ02'(!)           = ''              | ''                 | 'CV+10^0KZ02'              |'L_HCB7650-101_7-6X7-5'| 'NA'                           | 'IO'       | 'IND SMD 100NH 10% 35A(HCB7650-101)'            | 'CHIP'         | ''          | ''   | '20170830'  
 '1.0UH/7A'                     | 'SMLF'     | 'IND'    | 'CV-1070MZ20'(!)           = ''              | ''                 | 'CV-1070MZ20'              |'L_MMD-04BZ-1R5M-X2'| '1.0UH/7A'                     | 'DISCRETE' | 'IND SMD 1.0UH 20% 7A(MMD-04BZ-1R0M-X2Q)'       | 'CHIP'         | ''          | ''   | '20170907'  
 '1.0UH/7A'                     | 'SMLF'     | 'EMPTY'  | 'CV-1070MZ20'(!)           = ''              | ''                 | 'CV-1070MZ20'              |'L_MMD-04BZ-1R5M-X2'| 'NA'                           | 'IO'       | 'IND SMD 1.0UH 20% 7A(MMD-04BZ-1R0M-X2Q)'       | 'CHIP'         | ''          | ''   | '20170907'  
 '180NH/70A'                    | 'SMLF'     | 'IND'    | 'CV+18^0KZ09'(!)           = 'End of Design' | 'P/N Release'      | 'CV+18^0KZ09'              |'L_HCUVE768012-171_7-6X8-1'| '180NH/70A'                    | 'DISCRETE' | 'IND SMD 180NH 10% 70A(HCUVE768012D-181)'       | 'CHIP'         | ''          | ''   | '20170901'  
 '180NH/70A'                    | 'SMLF'     | 'EMPTY'  | 'CV+18^0KZ09'(!)           = 'End of Design' | 'P/N Release'      | 'CV+18^0KZ09'              |'L_HCUVE768012-171_7-6X8-1'| 'NA'                           | 'IO'       | 'IND SMD 180NH 10% 70A(HCUVE768012D-181)'       | 'CHIP'         | ''          | ''   | '20170901'  
 '180NH/74A'                    | 'SMLF'     | 'IND'    | 'CV+18^0KZ08'(!)           = ''              | ''                 | 'CV+18^0KZ08'              |'L_HCUVE768012-171_7-6X8-1'| '180NH/74A'                    | 'DISCRETE' | 'IND SMD 180NH 10% 74A(HCUVE768012-181)'        | 'CHIP'         | ''          | ''   | '20170901'  
 '180NH/74A'                    | 'SMLF'     | 'EMPTY'  | 'CV+18^0KZ08'(!)           = ''              | ''                 | 'CV+18^0KZ08'              |'L_HCUVE768012-171_7-6X8-1'| 'NA'                           | 'IO'       | 'IND SMD 180NH 10% 74A(HCUVE768012-181)'        | 'CHIP'         | ''          | ''   | '20170901'  
 '210NH/59A'                    | 'SMLF'     | 'IND'    | 'CV+21^0KZ03'(!)           = 'End of Design' | 'P/N Release'      | 'CV+21^0KZ03'              |'L_HCUVE768012-171_7-6X8-1'| '210N/59A'                     | 'DISCRETE' | 'IND SMD 210NH 10% 59A(HCUVE768012D-211)'       | 'CHIP'         | ''          | ''   | '20170901'  
 '210NH/59A'                    | 'SMLF'     | 'EMPTY'  | 'CV+21^0KZ03'(!)           = 'End of Design' | 'P/N Release'      | 'CV+21^0KZ03'              |'L_HCUVE768012-171_7-6X8-1'| 'NA'                           | 'IO'       | 'IND SMD 210NH 10% 59A(HCUVE768012D-211)'       | 'CHIP'         | ''          | ''   | '20170901'  
 '210NH/61A'                    | 'SMLF'     | 'IND'    | 'CV+21^0KZ02'(!)           = ''              | ''                 | 'CV+21^0KZ02'              |'L_HCUVE768012-171_7-6X8-1'| '210N/61A'                     | 'DISCRETE' | 'IND SMD 210NH 10% 61A(HCUVE768012-211)'        | 'CHIP'         | ''          | ''   | '20170901'  
 '210NH/61A'                    | 'SMLF'     | 'EMPTY'  | 'CV+21^0KZ02'(!)           = ''              | ''                 | 'CV+21^0KZ02'              |'L_HCUVE768012-171_7-6X8-1'| 'NA'                           | 'IO'       | 'IND SMD 210NH 10% 61A(HCUVE768012-211)'        | 'CHIP'         | ''          | ''   | '20170901'  
 '170NH/79A'                    | 'SMLF'     | 'IND'    | 'CV+17^0KZ01'(!)           = ''              | ''                 | 'CV+17^0KZ01'              |'L_HCUVE768012-171_7-6X8-1'| '170NH/79A'                    | 'DISCRETE' | 'IND SMD 170NH 10% 79A(HCUVE768012-171)'        | 'CHIP'         | ''          | ''   | '20161222'  
 '170NH/79A'                    | 'SMLF'     | 'EMPTY'  | 'CV+17^0KZ01'(!)           = ''              | ''                 | 'CV+17^0KZ01'              |'L_HCUVE768012-171_7-6X8-1'| 'NA'                           | 'IO'       | 'IND SMD 170NH 10% 79A(HCUVE768012-171)'        | 'CHIP'         | ''          | ''   | '20161222'  
 '170NH/75A'                    | 'SMLF'     | 'IND'    | 'CV+17^0KZ02'(!)           = 'End of Design' | 'Comp-Approve'     | 'CV+17^0KZ02'              |'L_HCUVE768012-171_7-6X8-1'| '170NH/75A'                    | 'DISCRETE' | 'IND SMD 170NH 10% 75A(HCUVE768012D-171)'       | 'CHIP'         | ''          | ''   | '20161222'  
 '170NH/75A'                    | 'SMLF'     | 'EMPTY'  | 'CV+17^0KZ02'(!)           = 'End of Design' | 'Comp-Approve'     | 'CV+17^0KZ02'              |'L_HCUVE768012-171_7-6X8-1'| 'NA'                           | 'IO'       | 'IND SMD 170NH 10% 75A(HCUVE768012D-171)'       | 'CHIP'         | ''          | ''   | '20161222'  
 '270NH/48A'                    | 'SMLF'     | 'IND'    | 'CV+27^0KZ16'(!)           = ''              | ''                 | 'CV+27^0KZ16'              |'L_HCUVE768012-171_7-6X8-1'| '270NH/48A'                    | 'DISCRETE' | 'IND SMD 270NH 10% 48A(HCUVE768012-271)'        | 'CHIP'         | ''          | ''   | '20161223'  
 '270NH/48A'                    | 'SMLF'     | 'EMPTY'  | 'CV+27^0KZ16'(!)           = ''              | ''                 | 'CV+27^0KZ16'              |'L_HCUVE768012-171_7-6X8-1'| 'NA'                           | 'IO'       | 'IND SMD 270NH 10% 48A(HCUVE768012-271)'        | 'CHIP'         | ''          | ''   | '20161223'  
 '270NH/46A'                    | 'SMLF'     | 'IND'    | 'CV+27^0KZ17'(!)           = ''              | ''                 | 'CV+27^0KZ17'              |'L_HCUVE768012-171_7-6X8-1'| '270NH/46A'                    | 'DISCRETE' | 'IND SMD 270NH 10% 46A(HCUVE768012D-271)'       | 'CHIP'         | ''          | ''   | '20161223'  
 '270NH/46A'                    | 'SMLF'     | 'EMPTY'  | 'CV+27^0KZ17'(!)           = ''              | ''                 | 'CV+27^0KZ17'              |'L_HCUVE768012-171_7-6X8-1'| 'NA'                           | 'IO'       | 'IND SMD 270NH 10% 46A(HCUVE768012D-271)'       | 'CHIP'         | ''          | ''   | '20161223'  
 '220NH/59A'                    | 'SMLF'     | 'IND'    | 'CV+22^0KZ21'(!)           = ''              | ''                 | 'CV+22^0KZ21'              |'L_HCUVE768012-171_7-6X8-1'| '220NH/59A'                    | 'DISCRETE' | 'IND SMD 220NH 10% 59A(HCUVE768012-221)'        | 'CHIP'         | ''          | ''   | '20161223'  
 '220NH/59A'                    | 'SMLF'     | 'EMPTY'  | 'CV+22^0KZ21'(!)           = ''              | ''                 | 'CV+22^0KZ21'              |'L_HCUVE768012-171_7-6X8-1'| 'NA'                           | 'IO'       | 'IND SMD 220NH 10% 59A(HCUVE768012-221)'        | 'CHIP'         | ''          | ''   | '20161223'  
 '220NH/57A'                    | 'SMLF'     | 'IND'    | 'CV+22^0KZ22'(!)           = 'End of Design' | 'Comp-Approve'     | 'CV+22^0KZ22'              |'L_HCUVE768012-171_7-6X8-1'| '220NH/57A'                    | 'DISCRETE' | 'IND SMD 220NH 10% 57A(HCUVE768012D-221)'       | 'CHIP'         | ''          | ''   | '20161223'  
 '220NH/57A'                    | 'SMLF'     | 'EMPTY'  | 'CV+22^0KZ22'(!)           = 'End of Design' | 'Comp-Approve'     | 'CV+22^0KZ22'              |'L_HCUVE768012-171_7-6X8-1'| 'NA'                           | 'IO'       | 'IND SMD 220NH 10% 57A(HCUVE768012D-221)'       | 'CHIP'         | ''          | ''   | '20161223'  
 '320NH/38A'                    | 'SMLF'     | 'IND'    | 'CV+32^0KZ10'(!)           = ''              | ''                 | 'CV+32^0KZ10'              |'L_HCUVE768012-171_7-6X8-1'| '320NH/38A'                    | 'DISCRETE' | 'IND SMD 320NH 10% 38A(HCUVE768012-321)'        | 'CHIP'         | ''          | ''   | '20161223'  
 '320NH/38A'                    | 'SMLF'     | 'EMPTY'  | 'CV+32^0KZ10'(!)           = ''              | ''                 | 'CV+32^0KZ10'              |'L_HCUVE768012-171_7-6X8-1'| 'NA'                           | 'IO'       | 'IND SMD 320NH 10% 38A(HCUVE768012-321)'        | 'CHIP'         | ''          | ''   | '20161223'  
 '320NH/37A'                    | 'SMLF'     | 'IND'    | 'CV+32^0KZ11'(!)           = 'End of Design' | 'Comp-Approve'     | 'CV+32^0KZ11'              |'L_HCUVE768012-171_7-6X8-1'| '320NH/37A'                    | 'DISCRETE' | 'IND SMD 320NH 10% 37A(HCUVE768012D-321)'       | 'CHIP'         | ''          | ''   | '20161223'  
 '320NH/37A'                    | 'SMLF'     | 'EMPTY'  | 'CV+32^0KZ11'(!)           = 'End of Design' | 'Comp-Approve'     | 'CV+32^0KZ11'              |'L_HCUVE768012-171_7-6X8-1'| 'NA'                           | 'IO'       | 'IND SMD 320NH 10% 37A(HCUVE768012D-321)'       | 'CHIP'         | ''          | ''   | '20161223'  
 'GMLB-160808-0030S-N8/5A'      | 'SMLF'     | 'IND'    | 'CX080030000'(!)           = ''              | ''                 | 'CX080030000'              |'L0603'| 'GMLB-160808-0030S-N8/5A'      | 'DISCRETE' | 'EMIFILT CHIP GMLB-160808-0030S-N8(30,5A)'      | 'CHIP'         | ''          | ''   | '20170921'  
 'GMLB-160808-0030S-N8/5A'      | 'SMLF'     | 'EMPTY'  | 'CX080030000'(!)           = ''              | ''                 | 'CX080030000'              |'L0603'| 'NA'                           | 'IO'       | 'EMIFILT CHIP GMLB-160808-0030S-N8(30,5A)'      | 'CHIP'         | ''          | ''   | '20170921'  
 'BLM18BB221SN1D/0.5A'          | 'SMLF'     | 'IND'    | 'CX8BB221007'(!)           = ''              | ''                 | 'CX8BB221007'              |'L0603'| 'BLM18BB221SN1D/0.5A'          | 'DISCRETE' | 'EMI FILTER CHIP BLM18BB221SN1D(10,0.5A)'       | 'CHIP'         | ''          | ''   | '20170925'  
 'BLM18BB221SN1D/0.5A'          | 'SMLF'     | 'EMPTY'  | 'CX8BB221007'(!)           = ''              | ''                 | 'CX8BB221007'              |'L0603'| 'NA'                           | 'IO'       | 'EMI FILTER CHIP BLM18BB221SN1D(10,0.5A)'       | 'CHIP'         | ''          | ''   | '20170925'  
 '330NH/28A'                    | 'SMLF'     | 'IND'    | 'CV+33T0KZ00'(!)           = ''              | ''                 | 'CV+33T0KZ00'              |'L_HCUVD6270_6-2X5-5'| '330NH/28A'                    | 'DISCRETE' | 'IND SMD 330NH 10% 28A(HCUVD6270-331QL)'        | 'CHIP'         | ''          | ''   | '20170930'  
 '330NH/28A'                    | 'SMLF'     | 'EMPTY'  | 'CV+33T0KZ00'(!)           = ''              | ''                 | 'CV+33T0KZ00'              |'L_HCUVD6270_6-2X5-5'| 'NA'                           | 'IO'       | 'IND SMD 330NH 10% 28A(HCUVD6270-331QL)'        | 'CHIP'         | ''          | ''   | '20170930'  
 '470NH/19A'                    | 'SMLF'     | 'IND'    | 'CV+47J0KZ00'(!)           = ''              | ''                 | 'CV+47J0KZ00'              |'L_HCUVD6270_6-2X5-5'| '470NH/19A'                    | 'DISCRETE' | 'IND SMD 470NH 10% 19A(HCUVD6270-471QL)'        | 'CHIP'         | ''          | ''   | '20170930'  
 '470NH/19A'                    | 'SMLF'     | 'EMPTY'  | 'CV+47J0KZ00'(!)           = ''              | ''                 | 'CV+47J0KZ00'              |'L_HCUVD6270_6-2X5-5'| 'NA'                           | 'IO'       | 'IND SMD 470NH 10% 19A(HCUVD6270-471QL)'        | 'CHIP'         | ''          | ''   | '20170930'  
 '220NH/40A'                    | 'SMLF'     | 'IND'    | 'CV+22^0KZ24'(!)           = ''              | ''                 | 'CV+22^0KZ24'              |'L_HCUVD6270_6-2X5-5'| '220NH/40A'                    | 'DISCRETE' | 'IND SMD 220NH 10% 40A(HCUVD6270-221QL)'        | 'CHIP'         | ''          | ''   | '20170930'  
 '220NH/40A'                    | 'SMLF'     | 'EMPTY'  | 'CV+22^0KZ24'(!)           = ''              | ''                 | 'CV+22^0KZ24'              |'L_HCUVD6270_6-2X5-5'| 'NA'                           | 'IO'       | 'IND SMD 220NH 10% 40A(HCUVD6270-221QL)'        | 'CHIP'         | ''          | ''   | '20170930'  
 '180NH/51A'                    | 'SMLF'     | 'IND'    | 'CV+18^0KZ10'(!)           = ''              | ''                 | 'CV+18^0KZ10'              |'L_HCUVD6270_6-2X5-5'| '180NH/51A'                    | 'DISCRETE' | 'IND SMD 180NH 10% 51A(HCUVD6270-181QL)'        | 'CHIP'         | ''          | ''   | '20170930'  
 '180NH/51A'                    | 'SMLF'     | 'EMPTY'  | 'CV+18^0KZ10'(!)           = ''              | ''                 | 'CV+18^0KZ10'              |'L_HCUVD6270_6-2X5-5'| 'NA'                           | 'IO'       | 'IND SMD 180NH 10% 51A(HCUVD6270-181QL)'        | 'CHIP'         | ''          | ''   | '20170930'  
 '150NH/61A'                    | 'SMLF'     | 'IND'    | 'CV+15^0KZ14'(!)           = ''              | ''                 | 'CV+15^0KZ14'              |'L_HCUVD6270_6-2X5-7'| '150NH/61A'                    | 'DISCRETE' | 'IND SMD 150NH 10% 61A(HCUVD6270-151QL)'        | 'CHIP'         | ''          | ''   | '20170930'  
 '150NH/61A'                    | 'SMLF'     | 'EMPTY'  | 'CV+15^0KZ14'(!)           = ''              | ''                 | 'CV+15^0KZ14'              |'L_HCUVD6270_6-2X5-7'| 'NA'                           | 'IO'       | 'IND SMD 150NH 10% 61A(HCUVD6270-151QL)'        | 'CHIP'         | ''          | ''   | '20170930'  
 'BLM18BA100SN1D/500MA'         | 'SMLF'     | 'IND'    | 'CX8BA100001'(!)           = ''              | ''                 | 'CX8BA100001'              |'L0603'| 'BLM18BA100SN1D/500MA'         | 'DISCRETE' | 'EMI FILTER BLM18BA100SN1D(10,500MA)'           | 'CHIP'         | ''          | ''   | '20171002'  
 'BLM18BA100SN1D/500MA'         | 'SMLF'     | 'EMPTY'  | 'CX8BA100001'(!)           = ''              | ''                 | 'CX8BA100001'              |'L0603'| 'NA'                           | 'IO'       | 'EMI FILTER BLM18BA100SN1D(10,500MA)'           | 'CHIP'         | ''          | ''   | '20171002'  
 '0.15UH/26A'                   | 'SMLF'     | 'IND'    | 'CV+15R0MZ00'(!)           = ''              | ''                 | 'CV+15R0MZ00'              |'L_PCMS063T_6-6X6-6'| '0.15UH/26A'                   | 'DISCRETE' | 'IND SMD 0.15UH 20% 26A(PCMS063T-R15MN1R)'      | 'CHIP'         | ''          | ''   | '20171017'  
 '0.15UH/26A'                   | 'SMLF'     | 'EMPTY'  | 'CV+15R0MZ00'(!)           = ''              | ''                 | 'CV+15R0MZ00'              |'L_PCMS063T_6-6X6-6'| 'NA'                           | 'IO'       | 'IND SMD 0.15UH 20% 26A(PCMS063T-R15MN1R)'      | 'CHIP'         | ''          | ''   | '20171017'  
 'HCB1608KF-221T25/2.5A'        | 'SMLF'     | 'IND'    | 'CX221T25000'(!)           = ''              | ''                 | 'CX221T25000'              |'L0603'| 'HCB1608KF-221T25/2.5A'        | 'DISCRETE' | 'EMI FILTER HCB1608KF-221T25(220,2.5A)'         | 'CHIP'         | ''          | ''   | '20171027'  
 'HCB1608KF-221T25/2.5A'        | 'SMLF'     | 'EMPTY'  | 'CX221T25000'(!)           = ''              | ''                 | 'CX221T25000'              |'L0603'| 'NA'                           | 'IO'       | 'EMI FILTER HCB1608KF-221T25(220,2.5A)'         | 'CHIP'         | ''          | ''   | '20171027'  
 '150NH/86A'                    | 'SMLF'     | 'IND'    | 'CV+15^0KZ15'(!)           = 'End of Design' | 'Comp-Approve'     | 'CV+15^0KZ15'              |'L_HCUVE768012-171_7-6X8-1'| '150NH/86A'                    | 'DISCRETE' | 'IND SMD 150NH 10% 86A(HCUVE768012D-151)'       | 'CHIP'         | ''          | ''   | '20171030'  
 '150NH/86A'                    | 'SMLF'     | 'EMPTY'  | 'CV+15^0KZ15'(!)           = 'End of Design' | 'Comp-Approve'     | 'CV+15^0KZ15'              |'L_HCUVE768012-171_7-6X8-1'| 'NA'                           | 'IO'       | 'IND SMD 150NH 10% 86A(HCUVE768012D-151)'       | 'CHIP'         | ''          | ''   | '20171030'  
 '180NH/64A'                    | 'SMLF'     | 'IND'    | 'CV+18^0KZ07'(!)           = ''              | ''                 | 'CV+18^0KZ07'              |'L_HCUVE966490D-121'| '180NH/64A'                    | 'DISCRETE' | 'IND SMD 180NH 10% 64A(HCUVE966490-181)'        | 'CHIP'         | ''          | ''   | '20171103'  
 '180NH/64A'                    | 'SMLF'     | 'EMPTY'  | 'CV+18^0KZ07'(!)           = ''              | ''                 | 'CV+18^0KZ07'              |'L_HCUVE966490D-121'| 'NA'                           | 'IO'       | 'IND SMD 180NH 10% 64A(HCUVE966490-181)'        | 'CHIP'         | ''          | ''   | '20171103'  
 '0.47UH/9.5A'                  | 'SMLF'     | 'IND'    | 'CV+4795MZ03'(!)           = ''              | ''                 | 'CV+4795MZ03'              |'L_CMLS041B_4-4X4-2'| '0.47UH/9.5A'                  | 'DISCRETE' | 'IND SMD 0.47UH20%9.5A(CMME041B-R47MS)'         | 'CHIP'         | ''          | ''   | '20171107'  
 '0.47UH/9.5A'                  | 'SMLF'     | 'EMPTY'  | 'CV+4795MZ03'(!)           = ''              | ''                 | 'CV+4795MZ03'              |'L_CMLS041B_4-4X4-2'| 'NA'                           | 'IO'       | 'IND SMD 0.47UH20%9.5A(CMME041B-R47MS)'         | 'CHIP'         | ''          | ''   | '20171107'  
 '1UH/6.5A'                     | 'SMLF'     | 'IND'    | 'CV-1065MZ03'(!)           = ''              | ''                 | 'CV-1065MZ03'              |'L_MMD-05AEN1R0M-X2Q_5-15X5-18'| '1UH/6.5A'                     | 'DISCRETE' | 'IND SMD 1UH20%6.5A,MMD-05AEN1R0M-X2Q'          | 'CHIP'         | ''          | ''   | '20171107'  
 '1UH/6.5A'                     | 'SMLF'     | 'EMPTY'  | 'CV-1065MZ03'(!)           = ''              | ''                 | 'CV-1065MZ03'              |'L_MMD-05AEN1R0M-X2Q_5-15X5-18'| 'NA'                           | 'IO'       | 'IND SMD 1UH20%6.5A,MMD-05AEN1R0M-X2Q'          | 'CHIP'         | ''          | ''   | '20171107'  
 '90NH/114A'                    | 'SMLF'     | 'IND'    | 'CVA90^0KZ02'(!)           = 'End of Design' | 'Comp-Approve'     | 'CVA90^0KZ02'              |'L_HCUVE966490D-121'| '90NH/114A'                    | 'DISCRETE' | 'IND SMD 90NH 10% 114A(HCUVE966490D-900)'       | 'CHIP'         | ''          | ''   | '20171109'  
 '90NH/114A'                    | 'SMLF'     | 'EMPTY'  | 'CVA90^0KZ02'(!)           = 'End of Design' | 'Comp-Approve'     | 'CVA90^0KZ02'              |'L_HCUVE966490D-121'| 'NA'                           | 'IO'       | 'IND SMD 90NH 10% 114A(HCUVE966490D-900)'       | 'CHIP'         | ''          | ''   | '20171109'  
 '210NH/50A'                    | 'SMLF'     | 'IND'    | 'CV+21^0KZ01'(!)           = ''              | ''                 | 'CV+21^0KZ01'              |'L_HCUVE966490D-121'| '210NH/50A'                    | 'DISCRETE' | 'IND SMD 210NH 10% 50A(HCUVE966490-211'         | 'CHIP'         | ''          | ''   | '20171109'  
 '210NH/50A'                    | 'SMLF'     | 'EMPTY'  | 'CV+21^0KZ01'(!)           = ''              | ''                 | 'CV+21^0KZ01'              |'L_HCUVE966490D-121'| 'NA'                           | 'IO'       | 'IND SMD 210NH 10% 50A(HCUVE966490-211'         | 'CHIP'         | ''          | ''   | '20171109'  
 '700NH/50A'                    | 'SMLF'     | 'IND'    | 'CV+70^0KZ00'(!)           = ''              | ''                 | 'CV+70^0KZ00'              |'L_HCUVD1115_11X8'| '700NH/50A'                    | 'DISCRETE' | 'IND SMD 700NH 10% 50A(HCUVD1115-701)'          | 'CHIP'         | ''          | ''   | '20171109'  
 '700NH/50A'                    | 'SMLF'     | 'EMPTY'  | 'CV+70^0KZ00'(!)           = ''              | ''                 | 'CV+70^0KZ00'              |'L_HCUVD1115_11X8'| 'NA'                           | 'IO'       | 'IND SMD 700NH 10% 50A(HCUVD1115-701)'          | 'CHIP'         | ''          | ''   | '20171109'  
 '100NH/16A'                    | 'SMLF'     | 'IND'    | 'CV+10G0MZ08'(!)           = ''              | ''                 | 'CV+10G0MZ08'              |'L_MSI-500505-R10M-E_4-5X4-7'| '100NH/16A'                    | 'DISCRETE' | 'IND SMD 100NH 20% 16A(MSI-500505-R10M-E'       | 'CHIP'         | ''          | ''   | '20171113'  
 '100NH/16A'                    | 'SMLF'     | 'EMPTY'  | 'CV+10G0MZ08'(!)           = ''              | ''                 | 'CV+10G0MZ08'              |'L_MSI-500505-R10M-E_4-5X4-7'| 'NA'                           | 'IO'       | 'IND SMD 100NH 20% 16A(MSI-500505-R10M-E'       | 'CHIP'         | ''          | ''   | '20171113'  
 '200NH/52A'                    | 'SMLF'     | 'IND'    | 'CV+20^0KZ03'(!)           = ''              | ''                 | 'CV+20^0KZ03'              |'L_HCUVD6595-201_6-5X6-6'| '200NH/52A'                    | 'DISCRETE' | 'IND SMD 200NH 10% 52A(HCUVD6595-201)'          | 'CHIP'         | ''          | ''   | '20171114'  
 '200NH/52A'                    | 'SMLF'     | 'EMPTY'  | 'CV+20^0KZ03'(!)           = ''              | ''                 | 'CV+20^0KZ03'              |'L_HCUVD6595-201_6-5X6-6'| 'NA'                           | 'IO'       | 'IND SMD 200NH 10% 52A(HCUVD6595-201)'          | 'CHIP'         | ''          | ''   | '20171114'  
 '0.22UH/64A'                   | 'SMLF'     | 'IND'    | 'CV+22^0KZ25'(!)           = ''              | ''                 | 'CV+22^0KZ25'              |'L_HCUVE117512D'| '0.22UH/64A'                   | 'DISCRETE' | 'IIND SMD 0.22UH 10% 64A(MSI-110812V-R22K'      | 'CHIP'         | ''          | ''   | '20171114'  
 '0.22UH/64A'                   | 'SMLF'     | 'EMPTY'  | 'CV+22^0KZ25'(!)           = ''              | ''                 | 'CV+22^0KZ25'              |'L_HCUVE117512D'| 'NA'                           | 'IO'       | 'IIND SMD 0.22UH 10% 64A(MSI-110812V-R22K'      | 'CHIP'         | ''          | ''   | '20171114'  
 '0.27UH/51A'                   | 'SMLF'     | 'IND'    | 'CV+27^0KZ18'(!)           = ''              | ''                 | 'CV+27^0KZ18'              |'L_HCUVE117512D'| '0.27UH/51A'                   | 'DISCRETE' | 'IND SMD 0.27UH 10% 51A(MSI-110812V-R27K'       | 'CHIP'         | ''          | ''   | '20171114'  
 '0.27UH/51A'                   | 'SMLF'     | 'EMPTY'  | 'CV+27^0KZ18'(!)           = ''              | ''                 | 'CV+27^0KZ18'              |'L_HCUVE117512D'| 'NA'                           | 'IO'       | 'IND SMD 0.27UH 10% 51A(MSI-110812V-R27K'       | 'CHIP'         | ''          | ''   | '20171114'  
 '0.25UH/56A'                   | 'SMLF'     | 'IND'    | 'CV+25^0MZ00'(!)           = ''              | ''                 | 'CV+25^0MZ00'              |'L_HCUVE117512D'| '0.25UH/56A'                   | 'DISCRETE' | 'IND SMD 0.25UH 20% 56A(MSI-110812V-R25M'       | 'CHIP'         | ''          | ''   | '20171114'  
 '0.25UH/56A'                   | 'SMLF'     | 'EMPTY'  | 'CV+25^0MZ00'(!)           = ''              | ''                 | 'CV+25^0MZ00'              |'L_HCUVE117512D'| 'NA'                           | 'IO'       | 'IND SMD 0.25UH 20% 56A(MSI-110812V-R25M'       | 'CHIP'         | ''          | ''   | '20171114'  
 '0.4UH/35A'                    | 'SMLF'     | 'IND'    | 'CV+40^0KZ03'(!)           = ''              | ''                 | 'CV+40^0KZ03'              |'L_HCUVE117512D'| '0.4UH/35A'                    | 'DISCRETE' | 'IND SMD 0.4UH 10% 35A(MSI-110812V-R40K'        | 'CHIP'         | ''          | ''   | '20171114'  
 '0.4UH/35A'                    | 'SMLF'     | 'EMPTY'  | 'CV+40^0KZ03'(!)           = ''              | ''                 | 'CV+40^0KZ03'              |'L_HCUVE117512D'| 'NA'                           | 'IO'       | 'IND SMD 0.4UH 10% 35A(MSI-110812V-R40K'        | 'CHIP'         | ''          | ''   | '20171114'  
 '0.6UH/21A'                    | 'SMLF'     | 'IND'    | 'CV+60L0MZ00'(!)           = ''              | ''                 | 'CV+60L0MZ00'              |'L_HCUVE117512D'| '0.6UH/21A'                    | 'DISCRETE' | 'IND SMD 0.6UH 20% 21A(MSI-110812V-R60M'        | 'CHIP'         | ''          | ''   | '20171114'  
 '0.6UH/21A'                    | 'SMLF'     | 'EMPTY'  | 'CV+60L0MZ00'(!)           = ''              | ''                 | 'CV+60L0MZ00'              |'L_HCUVE117512D'| 'NA'                           | 'IO'       | 'IND SMD 0.6UH 20% 21A(MSI-110812V-R60M'        | 'CHIP'         | ''          | ''   | '20171114'  
 '0.47UH/29A'                   | 'SMLF'     | 'IND'    | 'CV+47U0KZ00'(!)           = ''              | ''                 | 'CV+47U0KZ00'              |'L_HCUVE117512D'| '0.47UH/29A'                   | 'DISCRETE' | 'IND SMD 0.47UH 10% 29A(MSI-110812V-R47K'       | 'CHIP'         | ''          | ''   | '20171114'  
 '0.47UH/29A'                   | 'SMLF'     | 'EMPTY'  | 'CV+47U0KZ00'(!)           = ''              | ''                 | 'CV+47U0KZ00'              |'L_HCUVE117512D'| 'NA'                           | 'IO'       | 'IND SMD 0.47UH 10% 29A(MSI-110812V-R47K'       | 'CHIP'         | ''          | ''   | '20171114'  
 '0.32UH/43A'                   | 'SMLF'     | 'IND'    | 'CV+32^0KZ12'(!)           = ''              | ''                 | 'CV+32^0KZ12'              |'L_HCUVE117512D'| '0.32UH/43A'                   | 'DISCRETE' | 'IND SMD 0.32UH 10% 43A(MSI-110812V-R32K'       | 'CHIP'         | ''          | ''   | '20171114'  
 '0.32UH/43A'                   | 'SMLF'     | 'EMPTY'  | 'CV+32^0KZ12'(!)           = ''              | ''                 | 'CV+32^0KZ12'              |'L_HCUVE117512D'| 'NA'                           | 'IO'       | 'IND SMD 0.32UH 10% 43A(MSI-110812V-R32K'       | 'CHIP'         | ''          | ''   | '20171114'  
 '70NH/48A'                     | 'SMLF'     | 'IND'    | 'CVA70^0MZ03'(!)           = ''              | ''                 | 'CVA70^0MZ03'              |'L_MSI-600607_6-1X6'| '70NH/48A'                     | 'DISCRETE' | 'IND SMD 70NH 20% 48A(MSI-600607-70NM'          | 'CHIP'         | ''          | ''   | '20171114'  
 '70NH/48A'                     | 'SMLF'     | 'EMPTY'  | 'CVA70^0MZ03'(!)           = ''              | ''                 | 'CVA70^0MZ03'              |'L_MSI-600607_6-1X6'| 'NA'                           | 'IO'       | 'IND SMD 70NH 20% 48A(MSI-600607-70NM'          | 'CHIP'         | ''          | ''   | '20171114'  
 '80NH/40A'                     | 'SMLF'     | 'IND'    | 'CVA80^0MZ02'(!)           = ''              | ''                 | 'CVA80^0MZ02'              |'L_HCBS5265_5-2X5-2'| '80NH/40A'                     | 'DISCRETE' | 'IND SMD 80NH 20% 40A(MSI-500507-80NM'          | 'CHIP'         | ''          | ''   | '20171114'  
 '80NH/40A'                     | 'SMLF'     | 'EMPTY'  | 'CVA80^0MZ02'(!)           = ''              | ''                 | 'CVA80^0MZ02'              |'L_HCBS5265_5-2X5-2'| 'NA'                           | 'IO'       | 'IND SMD 80NH 20% 40A(MSI-500507-80NM'          | 'CHIP'         | ''          | ''   | '20171114'  
 '0.1UH/13A'                    | 'SMLF'     | 'IND'    | 'CV+10D0MZ00'(!)           = ''              | ''                 | 'CV+10D0MZ00'              |'L_MSI-400405_4X4-2'| '0.1UH/13A'                    | 'DISCRETE' | 'IND SMD 0.1UH 20% 13A(MSI-400405-R10M'         | 'CHIP'         | ''          | ''   | '20171114'  
 '0.1UH/13A'                    | 'SMLF'     | 'EMPTY'  | 'CV+10D0MZ00'(!)           = ''              | ''                 | 'CV+10D0MZ00'              |'L_MSI-400405_4X4-2'| 'NA'                           | 'IO'       | 'IND SMD 0.1UH 20% 13A(MSI-400405-R10M'         | 'CHIP'         | ''          | ''   | '20171114'  
 '150NH/75A'                    | 'SMLF'     | 'IND'    | 'CV+15^0KZ10'(!)           = 'End of Design' | 'Comp-Approve'     | 'CV+15^0KZ10'              |'L_HCUVE117512D_10-7X7-7'| '150NH/75A'                    | 'DISCRETE' | 'IND SMD 150NH 10% 75A(HCUVE117512D-151)'       | 'CHIP'         | ''          | ''   | '20160608'  
 '150NH/75A'                    | 'SMLF'     | 'EMPTY'  | 'CV+15^0KZ10'(!)           = 'End of Design' | 'Comp-Approve'     | 'CV+15^0KZ10'              |'L_HCUVE117512D_10-7X7-7'| 'NA'                           | 'IO'       | 'IND SMD 150NH 10% 75A(HCUVE117512D-151)'       | 'CHIP'         | ''          | ''   | '20160608'  
 '180NH/76A'                    | 'SMLF'     | 'IND'    | 'CV+18^0KZ11'(!)           = 'End of Design' | 'Comp-Approve'     | 'CV+18^0KZ11'              |'L_HCUVE117512D_10-7X7-7'| '180NH/76A'                    | 'DISCRETE' | 'IND SMD 180NH 10% 76A(HCUVE117512D-181)'       | 'CHIP'         | ''          | ''   | '20171117'  
 '180NH/76A'                    | 'SMLF'     | 'EMPTY'  | 'CV+18^0KZ11'(!)           = 'End of Design' | 'Comp-Approve'     | 'CV+18^0KZ11'              |'L_HCUVE117512D_10-7X7-7'| 'NA'                           | 'IO'       | 'IND SMD 180NH 10% 76A(HCUVE117512D-181)'       | 'CHIP'         | ''          | ''   | '20171117'  
 '220NH/0.2A'                   | 'SMLF'     | 'IND'    | 'CV+2202GZ00'(!)           = ''              | ''                 | 'CV+2202GZ00'              |'L0603'| '220NH/0.2A'                   | 'DISCRETE' | 'IND SMD 220NH 2% 0.2A(LQW18ASR22G0ZD)AEC'      | 'CHIP'         | ''          | ''   | '20171120'  
 '220NH/0.2A'                   | 'SMLF'     | 'EMPTY'  | 'CV+2202GZ00'(!)           = ''              | ''                 | 'CV+2202GZ00'              |'L0603'| 'NA'                           | 'IO'       | 'IND SMD 220NH 2% 0.2A(LQW18ASR22G0ZD)AEC'      | 'CHIP'         | ''          | ''   | '20171120'  
 '1.0UH/3A'                     | 'SMLF'     | 'IND'    | 'CV-1030MZ01'(!)           = ''              | ''                 | 'CV-1030MZ01'              |'L_MLV-YT12N_2-5X2'| '1.0UH/3A'                     | 'DISCRETE' | 'IND SMD 1.0UH +-20% 3A MLV-YT12N1R0M-O1Q'      | 'CHIP'         | ''          | ''   | '20171121'  
 '1.0UH/3A'                     | 'SMLF'     | 'EMPTY'  | 'CV-1030MZ01'(!)           = ''              | ''                 | 'CV-1030MZ01'              |'L_MLV-YT12N_2-5X2'| 'NA'                           | 'IO'       | 'IND SMD 1.0UH +-20% 3A MLV-YT12N1R0M-O1Q'      | 'CHIP'         | ''          | ''   | '20171121'  
 '47UH/75MA'                    | 'SMLF'     | 'IND'    | 'CV04701KN03'(!)           = ''              | ''                 | 'CV04701KN03'              |'L0805_H62'| '47UH/75MA'                    | 'DISCRETE' | 'IND CHIP 47UH 10% 75MA(LB R2012T470K)'         | 'CHIP'         | ''          | ''   | '20171121'  
 '47UH/75MA'                    | 'SMLF'     | 'EMPTY'  | 'CV04701KN03'(!)           = ''              | ''                 | 'CV04701KN03'              |'L0805_H62'| 'NA'                           | 'IO'       | 'IND CHIP 47UH 10% 75MA(LB R2012T470K)'         | 'CHIP'         | ''          | ''   | '20171121'  
 'FCM1608KF-102T06/0.6A'        | 'SMLF'     | 'IND'    | 'CX102T06000'(!)           = 'End of Design' | 'Comp-Approve'     | 'CX102T06000'              |'L0603'| 'FCM1608KF-102T06/0.6A'        | 'DISCRETE' | 'EMI FILTER FCM1608KF-102T06(1000,0.6A)'        | 'CHIP'         | ''          | ''   | '20171123'  
 'FCM1608KF-102T06/0.6A'        | 'SMLF'     | 'EMPTY'  | 'CX102T06000'(!)           = 'End of Design' | 'Comp-Approve'     | 'CX102T06000'              |'L0603'| 'NA'                           | 'IO'       | 'EMI FILTER FCM1608KF-102T06(1000,0.6A)'        | 'CHIP'         | ''          | ''   | '20171123'  
 '0.16UH/84A'                   | 'SMLF'     | 'IND'    | 'CV+16^0KZ00'(!)           = ''              | ''                 | 'CV+16^0KZ00'              |'L_HCUVE117512D_10-7X7-7'| '0.16UH/84A'                   | 'DISCRETE' | 'IND SMD 0.16UH 10% 84A(MSI-110812V-R16K'       | 'CHIP'         | ''          | ''   | '20171204'  
 '0.16UH/84A'                   | 'SMLF'     | 'EMPTY'  | 'CV+16^0KZ00'(!)           = ''              | ''                 | 'CV+16^0KZ00'              |'L_HCUVE117512D_10-7X7-7'| 'NA'                           | 'IO'       | 'IND SMD 0.16UH 10% 84A(MSI-110812V-R16K'       | 'CHIP'         | ''          | ''   | '20171204'  
 '0.17UH/78A'                   | 'SMLF'     | 'IND'    | 'CV+17^0KZ03'(!)           = ''              | ''                 | 'CV+17^0KZ03'              |'L_HCUVE117512D_10-7X7-7'| '0.17UH/78A'                   | 'DISCRETE' | 'IND SMD 0.17UH 10% 78A(MSI-110812V-R17K'       | 'CHIP'         | ''          | ''   | '20171204'  
 '0.17UH/78A'                   | 'SMLF'     | 'EMPTY'  | 'CV+17^0KZ03'(!)           = ''              | ''                 | 'CV+17^0KZ03'              |'L_HCUVE117512D_10-7X7-7'| 'NA'                           | 'IO'       | 'IND SMD 0.17UH 10% 78A(MSI-110812V-R17K'       | 'CHIP'         | ''          | ''   | '20171204'  
 '0.18UH/76A'                   | 'SMLF'     | 'IND'    | 'CV+18^0KZ12'(!)           = ''              | ''                 | 'CV+18^0KZ12'              |'L_HCUVE117512D_10-7X7-7'| '0.18UH/76A'                   | 'DISCRETE' | 'IND SMD 0.18UH 10% 76A(MSI-110812V-R18K'       | 'CHIP'         | ''          | ''   | '20171204'  
 '0.18UH/76A'                   | 'SMLF'     | 'EMPTY'  | 'CV+18^0KZ12'(!)           = ''              | ''                 | 'CV+18^0KZ12'              |'L_HCUVE117512D_10-7X7-7'| 'NA'                           | 'IO'       | 'IND SMD 0.18UH 10% 76A(MSI-110812V-R18K'       | 'CHIP'         | ''          | ''   | '20171204'  
 '0.2UH/69A'                    | 'SMLF'     | 'IND'    | 'CV+20^0KZ05'(!)           = ''              | ''                 | 'CV+20^0KZ05'              |'L_HCUVE117512D'| '0.2UH/69A'                    | 'DISCRETE' | 'IND SMD 0.2UH 10% 69A(MSI-110812V-R20K'        | 'CHIP'         | ''          | ''   | '20171204'  
 '0.2UH/69A'                    | 'SMLF'     | 'EMPTY'  | 'CV+20^0KZ05'(!)           = ''              | ''                 | 'CV+20^0KZ05'              |'L_HCUVE117512D'| 'NA'                           | 'IO'       | 'IND SMD 0.2UH 10% 69A(MSI-110812V-R20K'        | 'CHIP'         | ''          | ''   | '20171204'  
 'BLM15PD121SN1D/1300MA'        | 'SMLF'     | 'IND'    | 'CX5PD121000'(!)           = ''              | ''                 | 'CX5PD121000'              |'L0402'| 'BLM15PD121SN1D/1300MA'        | 'DISCRETE' | 'EMI FILTER BLM15PD121SN1D(120OHM,1300MA)'      | 'CHIP'         | ''          | ''   | '20171207'  
 'BLM15PD121SN1D/1300MA'        | 'SMLF'     | 'EMPTY'  | 'CX5PD121000'(!)           = ''              | ''                 | 'CX5PD121000'              |'L0402'| 'NA'                           | 'IO'       | 'EMI FILTER BLM15PD121SN1D(120OHM,1300MA)'      | 'CHIP'         | ''          | ''   | '20171207'  
 'BLM18KG331SN1D/1.7A'          | 'SMLF'     | 'IND'    | 'CX8KG331000'(!)           = ''              | ''                 | 'CX8KG331000'              |'L0603'| 'BLM18KG331SN1D/1.7A'          | 'DISCRETE' | 'EMI FILTER BLM18KG331SN1D(330,1.7A)'           | 'CHIP'         | ''          | ''   | '20171212'  
 'BLM18KG331SN1D/1.7A'          | 'SMLF'     | 'EMPTY'  | 'CX8KG331000'(!)           = ''              | ''                 | 'CX8KG331000'              |'L0603'| 'NA'                           | 'IO'       | 'EMI FILTER BLM18KG331SN1D(330,1.7A)'           | 'CHIP'         | ''          | ''   | '20171212'  
 'BLM31KN471SN1L/4A'            | 'SMLF'     | 'IND'    | 'CX1KN471000'(!)           = ''              | ''                 | 'CX1KN471000'              |'L1206XB'| 'BLM31KN471SN1L/4A'            | 'DISCRETE' | 'EMI FILTER BEAD BLM31KN471SN1L(470,4A)'        | 'CHIP'         | ''          | ''   | '20171213'  
 'BLM31KN471SN1L/4A'            | 'SMLF'     | 'EMPTY'  | 'CX1KN471000'(!)           = ''              | ''                 | 'CX1KN471000'              |'L1206XB'| 'NA'                           | 'IO'       | 'EMI FILTER BEAD BLM31KN471SN1L(470,4A)'        | 'CHIP'         | ''          | ''   | '20171213'  
 '300NH/36A'                    | 'SMLF'     | 'IND'    | 'CV+30^0KZ13'(!)           = ''              | ''                 | 'CV+30^0KZ13'              |'L_HCUVD6595-201_6-5X6-6'| '300NH/36A'                    | 'DISCRETE' | 'IND SMD 300NH 10% 36A(HCUVD6595D-301LY)'       | 'CHIP'         | ''          | ''   | '20171218'  
 '300NH/36A'                    | 'SMLF'     | 'EMPTY'  | 'CV+30^0KZ13'(!)           = ''              | ''                 | 'CV+30^0KZ13'              |'L_HCUVD6595-201_6-5X6-6'| 'NA'                           | 'IO'       | 'IND SMD 300NH 10% 36A(HCUVD6595D-301LY)'       | 'CHIP'         | ''          | ''   | '20171218'  
 '110NH/124A'                   | 'SMLF'     | 'IND'    | 'CV+11^0KZ00'(!)           = ''              | ''                 | 'CV+11^0KZ00'              |'L_HCUVE117512D_10-7X7-7'| '110NH/124A'                   | 'DISCRETE' | 'IND SMD 110NH 10% 124A(HCUVE117512D-111)'      | 'CHIP'         | ''          | ''   | '20171222'  
 '110NH/124A'                   | 'SMLF'     | 'EMPTY'  | 'CV+11^0KZ00'(!)           = ''              | ''                 | 'CV+11^0KZ00'              |'L_HCUVE117512D_10-7X7-7'| 'NA'                           | 'IO'       | 'IND SMD 110NH 10% 124A(HCUVE117512D-111)'      | 'CHIP'         | ''          | ''   | '20171222'  
 '0.17UH/64A'                   | 'SMLF'     | 'IND'    | 'CV+17^0KZ04'(!)           = ''              | ''                 | 'CV+17^0KZ04'              |'L_HCUVE768012-171_7-6X8-1'| '0.17UH/64A'                   | 'DISCRETE' | 'IND SMD 0.17UH 10% 64A(MSI-800812V-R17K'       | 'CHIP'         | ''          | ''   | '20171226'  
 '0.17UH/64A'                   | 'SMLF'     | 'EMPTY'  | 'CV+17^0KZ04'(!)           = ''              | ''                 | 'CV+17^0KZ04'              |'L_HCUVE768012-171_7-6X8-1'| 'NA'                           | 'IO'       | 'IND SMD 0.17UH 10% 64A(MSI-800812V-R17K'       | 'CHIP'         | ''          | ''   | '20171226'  
 '0.22UH/48A'                   | 'SMLF'     | 'IND'    | 'CV+22^0KZ26'(!)           = ''              | ''                 | 'CV+22^0KZ26'              |'L_HCUVE768012-171_7-6X8-1'| '0.22UH/48A'                   | 'DISCRETE' | 'IND SMD 0.22UH 10% 48A(MSI-800812V-R22K'       | 'CHIP'         | ''          | ''   | '20171226'  
 '0.22UH/48A'                   | 'SMLF'     | 'EMPTY'  | 'CV+22^0KZ26'(!)           = ''              | ''                 | 'CV+22^0KZ26'              |'L_HCUVE768012-171_7-6X8-1'| 'NA'                           | 'IO'       | 'IND SMD 0.22UH 10% 48A(MSI-800812V-R22K'       | 'CHIP'         | ''          | ''   | '20171226'  
 '0.32UH/31A'                   | 'SMLF'     | 'IND'    | 'CV+32W0KZ00'(!)           = ''              | ''                 | 'CV+32W0KZ00'              |'L_HCUVE768012-171_7-6X8-1'| '0.32UH/31A'                   | 'DISCRETE' | 'IND SMD 0.32UH 10% 31A(MSI-800812V-R32K'       | 'CHIP'         | ''          | ''   | '20171226'  
 '0.32UH/31A'                   | 'SMLF'     | 'EMPTY'  | 'CV+32W0KZ00'(!)           = ''              | ''                 | 'CV+32W0KZ00'              |'L_HCUVE768012-171_7-6X8-1'| 'NA'                           | 'IO'       | 'IND SMD 0.32UH 10% 31A(MSI-800812V-R32K'       | 'CHIP'         | ''          | ''   | '20171226'  
 '1UH/7A'                       | 'SMLF'     | 'IND'    | 'CV-1070MZ08'(!)           = ''              | ''                 | 'CV-1070MZ08'              |'L_CMME053T_4-5X4-7'| '1UH/7A'                       | 'DISCRETE' | 'IND SMD 1UH +-20% 7A(PCMB053T--1R0MS)'         | 'CHIP'         | ''          | ''   | '20180119'  
 '1UH/7A'                       | 'SMLF'     | 'EMPTY'  | 'CV-1070MZ08'(!)           = ''              | ''                 | 'CV-1070MZ08'              |'L_CMME053T_4-5X4-7'| 'NA'                           | 'IO'       | 'IND SMD 1UH +-20% 7A(PCMB053T--1R0MS)'         | 'CHIP'         | ''          | ''   | '20180119'  
 '200UH/45A'                    | 'SMLF'     | 'IND'    | 'CV120^0KZ00'(!)           = ''              | 'End of Life'      | 'CV120^0KZ00'              |'L_HCUVD6270_6-2X5-5_EOL'| '200UH/45A'                    | 'DISCRETE' | 'IND SMD 200UH 10% 45A(HCUVD6270-201QL)'        | 'CHIP'         | ''          | ''   | '20180119'  
 '200UH/45A'                    | 'SMLF'     | 'EMPTY'  | 'CV120^0KZ00'(!)           = ''              | 'End of Life'      | 'CV120^0KZ00'              |'L_HCUVD6270_6-2X5-5_EOL'| 'NA'                           | 'IO'       | 'IND SMD 200UH 10% 45A(HCUVD6270-201QL)'        | 'CHIP'         | ''          | ''   | '20180119'  
 '220/2.2A'                     | 'SMLF'     | 'IND'    | 'CX8KG221000'(!)           = 'End of Design' | 'Comp-Approve'     | 'CX8KG221000'              |'L0603'| '220/2.2A'                     | 'DISCRETE' | 'EMI FILTER BLM18KG221SN1D(220,2.2A)'           | 'CHIP'         | ''          | ''   | '20180129'  
 '220/2.2A'                     | 'SMLF'     | 'EMPTY'  | 'CX8KG221000'(!)           = 'End of Design' | 'Comp-Approve'     | 'CX8KG221000'              |'L0603'| 'NA'                           | 'IO'       | 'EMI FILTER BLM18KG221SN1D(220,2.2A)'           | 'CHIP'         | ''          | ''   | '20180129'  
 '0.33UH/10A'                   | 'SMLF'     | 'IND'    | 'CV+33A0MZ02'(!)           = ''              | ''                 | 'CV+33A0MZ02'              |'L_MMD-06AEE_6-86X6-47'| '0.33UH/10A'                   | 'DISCRETE' | 'IND SMD 0.33UH 20% 10A MMD-06AEER33M-X5Q'      | 'CHIP'         | ''          | ''   | '20180205'  
 '0.33UH/10A'                   | 'SMLF'     | 'EMPTY'  | 'CV+33A0MZ02'(!)           = ''              | ''                 | 'CV+33A0MZ02'              |'L_MMD-06AEE_6-86X6-47'| 'NA'                           | 'IO'       | 'IND SMD 0.33UH 20% 10A MMD-06AEER33M-X5Q'      | 'CHIP'         | ''          | ''   | '20180205'  
 '0.68UH/13A'                   | 'SMLF'     | 'IND'    | 'CV+68D0MZ00'(!)           = ''              | ''                 | 'CV+68D0MZ00'              |'L_MMD-05AEH_5-49X5-18'| '0.68UH/13A'                   | 'DISCRETE' | 'IND SMD 0.68U,13A,20%(MMD-05AEHR68M-T1Q)'      | 'CHIP'         | ''          | ''   | '20180205'  
 '0.68UH/13A'                   | 'SMLF'     | 'EMPTY'  | 'CV+68D0MZ00'(!)           = ''              | ''                 | 'CV+68D0MZ00'              |'L_MMD-05AEH_5-49X5-18'| 'NA'                           | 'IO'       | 'IND SMD 0.68U,13A,20%(MMD-05AEHR68M-T1Q)'      | 'CHIP'         | ''          | ''   | '20180205'  
 'BLM15BA330SN1D/300MA'         | 'SMLF'     | 'IND'    | 'CX5BA330001'(!)           = ''              | ''                 | 'CX5BA330001'              |'L0402'| 'BLM15BA330SN1D/300MA'         | 'DISCRETE' | 'EMI FILTER BLM15BA330SN1D(33,300MA)0402'       | 'CHIP'         | ''          | ''   | '20180208'  
 'BLM15BA330SN1D/300MA'         | 'SMLF'     | 'EMPTY'  | 'CX5BA330001'(!)           = ''              | ''                 | 'CX5BA330001'              |'L0402'| 'NA'                           | 'IO'       | 'EMI FILTER BLM15BA330SN1D(33,300MA)0402'       | 'CHIP'         | ''          | ''   | '20180208'  
 'FCM1608VF-301T05/0.5A'        | 'SMLF'     | 'IND'    | 'CX301T05000'(!)           = ''              | ''                 | 'CX301T05000'              |'L0603'| 'FCM1608VF-301T05/0.5A'        | 'DISCRETE' | 'EMI FILTER FCM1608VF-301T05(300,0.5A)'         | 'CHIP'         | ''          | ''   | '20180312'  
 'FCM1608VF-301T05/0.5A'        | 'SMLF'     | 'EMPTY'  | 'CX301T05000'(!)           = ''              | ''                 | 'CX301T05000'              |'L0603'| 'NA'                           | 'IO'       | 'EMI FILTER FCM1608VF-301T05(300,0.5A)'         | 'CHIP'         | ''          | ''   | '20180312'  
 '220NH/75A'                    | 'SMLF'     | 'IND'    | 'CV+22^0KZ27'(!)           = 'End of Design' | 'Comp-Approve'     | 'CV+22^0KZ27'              |'L_HCUVE1112D-221_10-7X7-5'| '220NH/75A'                    | 'DISCRETE' | 'IND SMD 220NH 10% 75A(HCUVE1112D-221)'         | 'CHIP'         | ''          | ''   | '20180312'  
 '220NH/75A'                    | 'SMLF'     | 'EMPTY'  | 'CV+22^0KZ27'(!)           = 'End of Design' | 'Comp-Approve'     | 'CV+22^0KZ27'              |'L_HCUVE1112D-221_10-7X7-5'| 'NA'                           | 'IO'       | 'IND SMD 220NH 10% 75A(HCUVE1112D-221)'         | 'CHIP'         | ''          | ''   | '20180312'  
 '400NH/41A'                    | 'SMLF'     | 'IND'    | 'CV+40^0KZ04'(!)           = 'End of Design' | 'Comp-Release Qty' | 'CV+40^0KZ04'              |'L_HCUVE1112D-221_10-7X7-5'| '400NH/41A'                    | 'DISCRETE' | 'IND SMD 400NH 10% 41A(HCUVE1112D-401)'         | 'CHIP'         | ''          | ''   | '20180312'  
 '400NH/41A'                    | 'SMLF'     | 'EMPTY'  | 'CV+40^0KZ04'(!)           = 'End of Design' | 'Comp-Release Qty' | 'CV+40^0KZ04'              |'L_HCUVE1112D-221_10-7X7-5'| 'NA'                           | 'IO'       | 'IND SMD 400NH 10% 41A(HCUVE1112D-401)'         | 'CHIP'         | ''          | ''   | '20180312'  
 'MMZ1608R601AT/0.5A'           | 'SMLF'     | 'IND'    | 'CX08R601000'(!)           = 'End of Design' | 'End of Life'      | 'CX08R601000'              |'L0603_EOL'| 'MMZ1608R601AT/0.5A'           | 'DISCRETE' | 'EMI FILTER CHIP MMZ1608R601AT(600,0.5A)'       | 'CHIP'         | ''          | ''   | '20180313'  
 'MMZ1608R601AT/0.5A'           | 'SMLF'     | 'EMPTY'  | 'CX08R601000'(!)           = 'End of Design' | 'End of Life'      | 'CX08R601000'              |'L0603_EOL'| 'NA'                           | 'IO'       | 'EMI FILTER CHIP MMZ1608R601AT(600,0.5A)'       | 'CHIP'         | ''          | ''   | '20180313'  
 '4.7UH/210MA'                  | 'SMLF'     | 'IND'    | 'CV-4703MN13'(!)           = ''              | ''                 | 'CV-4703MN13'              |'L0806'| '4.7UH/210MA'                  | 'DISCRETE' | 'IND SMD 4.7UH,+-20%,210MA,LB2016T4R7M'         | 'CHIP'         | ''          | ''   | '20180313'  
 '4.7UH/210MA'                  | 'SMLF'     | 'EMPTY'  | 'CV-4703MN13'(!)           = ''              | ''                 | 'CV-4703MN13'              |'L0806'| 'NA'                           | 'IO'       | 'IND SMD 4.7UH,+-20%,210MA,LB2016T4R7M'         | 'CHIP'         | ''          | ''   | '20180313'  
 '3.3UH/2A'                     | 'SMLF'     | 'IND'    | 'CV-3320MZ05'(!)           = ''              | ''                 | 'CV-3320MZ05'              |'L_MLPS-4015W-3R3M-F_4X4'| '3.3UH/2A'                     | 'DISCRETE' | 'IND SMD 3.3UH 20% 2A(MLPS-4015W-3R3M-F)'       | 'CHIP'         | ''          | ''   | '20180313'  
 '3.3UH/2A'                     | 'SMLF'     | 'EMPTY'  | 'CV-3320MZ05'(!)           = ''              | ''                 | 'CV-3320MZ05'              |'L_MLPS-4015W-3R3M-F_4X4'| 'NA'                           | 'IO'       | 'IND SMD 3.3UH 20% 2A(MLPS-4015W-3R3M-F)'       | 'CHIP'         | ''          | ''   | '20180313'  
 '15N/250MA'                    | 'SMLF'     | 'IND'    | 'CVA1503JN77'(!)           = ''              | ''                 | 'CVA1503JN77'              |'L0402'| '15N/250MA'                    | 'DISCRETE' | 'IND CHIP 15N +-5% 250MA CLH1005T-15NJ-S'       | 'CHIP'         | ''          | ''   | '20180320'  
 '15N/250MA'                    | 'SMLF'     | 'EMPTY'  | 'CVA1503JN77'(!)           = ''              | ''                 | 'CVA1503JN77'              |'L0402'| 'NA'                           | 'IO'       | 'IND CHIP 15N +-5% 250MA CLH1005T-15NJ-S'       | 'CHIP'         | ''          | ''   | '20180320'  
 '22NH/350MA'                   | 'SMLF'     | 'IND'    | 'CVA2204JN02'(!)           = ''              | ''                 | 'CVA2204JN02'              |'L0402'| '22NH/350MA'                   | 'DISCRETE' | 'IND CHIP 22NH 5% 350MA(LQG15HS22NJ02D)'        | 'CHIP'         | ''          | ''   | '20180322'  
 '22NH/350MA'                   | 'SMLF'     | 'EMPTY'  | 'CVA2204JN02'(!)           = ''              | ''                 | 'CVA2204JN02'              |'L0402'| 'NA'                           | 'IO'       | 'IND CHIP 22NH 5% 350MA(LQG15HS22NJ02D)'        | 'CHIP'         | ''          | ''   | '20180322'  
 '1UH/7A'                       | 'SMLF'     | 'IND'    | 'CV-1070MZ07'(!)           = 'End of Design' | 'Comp-Release Qty' | 'CV-1070MZ07'              |'L_CMLE053T_4-85X4-7'| '1UH/7A'                       | 'DISCRETE' | 'IND SMD 1UH +-20% 7A(PIMB053T-1R0MS)'          | 'CHIP'         | ''          | ''   | '20180323'  
 '1UH/7A'                       | 'SMLF'     | 'EMPTY'  | 'CV-1070MZ07'(!)           = 'End of Design' | 'Comp-Release Qty' | 'CV-1070MZ07'              |'L_CMLE053T_4-85X4-7'| 'NA'                           | 'IO'       | 'IND SMD 1UH +-20% 7A(PIMB053T-1R0MS)'          | 'CHIP'         | ''          | ''   | '20180323'  
 '58NH/83A'                     | 'SMLF'     | 'IND'    | 'CVA58^0KZ00'(!)           = ''              | ''                 | 'CVA58^0KZ00'              |'L_FP0805R1-R06-R_6-5X7-49'| '58NH/83A'                     | 'DISCRETE' | 'IND SMD 58NH +-10% 83A(FP0805R1-R06-R)'        | 'CHIP'         | ''          | ''   | '20170705'  
 '58NH/83A'                     | 'SMLF'     | 'EMPTY'  | 'CVA58^0KZ00'(!)           = ''              | ''                 | 'CVA58^0KZ00'              |'L_FP0805R1-R06-R_6-5X7-49'| 'NA'                           | 'IO'       | 'IND SMD 58NH +-10% 83A(FP0805R1-R06-R)'        | 'CHIP'         | ''          | ''   | '20170705'  
 'GMLB-201209-0220P-N8/3A'      | 'SMLF'     | 'IND'    | 'CX090220001'(!)           = ''              | ''                 | 'CX090220001'              |'L0805_H44'| 'GMLB-201209-0220P-N8/3A'      | 'DISCRETE' | 'EMI FILTER GMLB-201209-0220P-N8(220,3A)'       | 'CHIP'         | ''          | ''   | '20180331'  
 'GMLB-201209-0220P-N8/3A'      | 'SMLF'     | 'EMPTY'  | 'CX090220001'(!)           = ''              | ''                 | 'CX090220001'              |'L0805_H44'| 'NA'                           | 'IO'       | 'EMI FILTER GMLB-201209-0220P-N8(220,3A)'       | 'CHIP'         | ''          | ''   | '20180331'  
 'BLM18HE102SN1D/0.6A'          | 'SMLF'     | 'IND'    | 'CX8HE102000'(!)           = ''              | ''                 | 'CX8HE102000'              |'L0603'| 'BLM18HE102SN1D/0.6A'          | 'DISCRETE' | 'EMI FILTER BLM18HE102SN1D(1000,0.6A)'          | 'CHIP'         | ''          | ''   | '20180402'  
 'BLM18HE102SN1D/0.6A'          | 'SMLF'     | 'EMPTY'  | 'CX8HE102000'(!)           = ''              | ''                 | 'CX8HE102000'              |'L0603'| 'NA'                           | 'IO'       | 'EMI FILTER BLM18HE102SN1D(1000,0.6A)'          | 'CHIP'         | ''          | ''   | '20180402'  
 '200NH/45A'                    | 'SMLF'     | 'IND'    | 'CV+20^0KZ06'(!)           = ''              | ''                 | 'CV+20^0KZ06'              |'L_HCUVD6270_6-2X5-5'| '200NH/45A'                    | 'DISCRETE' | 'IND SMD 200NH 10% 45A(HCUVD6270-201QL)'        | 'CHIP'         | ''          | ''   | '20180409'  
 '200NH/45A'                    | 'SMLF'     | 'EMPTY'  | 'CV+20^0KZ06'(!)           = ''              | ''                 | 'CV+20^0KZ06'              |'L_HCUVD6270_6-2X5-5'| 'NA'                           | 'IO'       | 'IND SMD 200NH 10% 45A(HCUVD6270-201QL)'        | 'CHIP'         | ''          | ''   | '20180409'  
 '72NH/65A'                     | 'SMLF'     | 'IND'    | 'CVA72^0KZ01'(!)           = ''              | ''                 | 'CVA72^0KZ01'              |'L_FP0805R1-R06-R_6-5X7-49'| '72NH/65A'                     | 'DISCRETE' | 'IND SMD 72NH +-10% 65A(FP0805R1-R07-R)'        | 'CHIP'         | ''          | ''   | '20180418'  
 '72NH/65A'                     | 'SMLF'     | 'EMPTY'  | 'CVA72^0KZ01'(!)           = ''              | ''                 | 'CVA72^0KZ01'              |'L_FP0805R1-R06-R_6-5X7-49'| 'NA'                           | 'IO'       | 'IND SMD 72NH +-10% 65A(FP0805R1-R07-R)'        | 'CHIP'         | ''          | ''   | '20180418'  
 '47UH/4.4A'                    | 'SMLF'     | 'IND'    | 'CV04744MZ00'(!)           = ''              | ''                 | 'CV04744MZ00'              |'L_MSCDRI104RXA'| '47UH/4.4A'                    | 'DISCRETE' | 'IND SMD 47UH+-20%4.4A(MSCDRI-104R-470M)'       | 'CHIP'         | ''          | ''   | '20150731'  
 '47UH/4.4A'                    | 'SMLF'     | 'EMPTY'  | 'CV04744MZ00'(!)           = ''              | ''                 | 'CV04744MZ00'              |'L_MSCDRI104RXA'| 'NA'                           | 'IO'       | 'IND SMD 47UH+-20%4.4A(MSCDRI-104R-470M)'       | 'CHIP'         | ''          | ''   | '20150731'  
 'MLB-160808-0100P-N1A/3A'      | 'SMLF'     | 'IND'    | 'CX00100P009'(!)           = ''              | ''                 | 'CX00100P009'              |'L0603'| 'MLB-160808-0100P-N1A/3A'      | 'DISCRETE' | 'EMI FILTER MLB-160808-0100P-N1A(100,3A)'       | 'CHIP'         | ''          | ''   | '20180507'  
 'MLB-160808-0100P-N1A/3A'      | 'SMLF'     | 'EMPTY'  | 'CX00100P009'(!)           = ''              | ''                 | 'CX00100P009'              |'L0603'| 'NA'                           | 'IO'       | 'EMI FILTER MLB-160808-0100P-N1A(100,3A)'       | 'CHIP'         | ''          | ''   | '20180507'  
 '470NH/38A'                    | 'SMLF'     | 'IND'    | 'CV+47^0KZ07'(!)           = 'End of Design' | 'Comp-Release Qty' | 'CV+47^0KZ07'              |'L_HCUVD8095D-102KBQL_8X8'| '470NH/38A'                    | 'DISCRETE' | 'IND SMD 470NH 10% 38A(HCUVD8095D-471QL)'       | 'CHIP'         | ''          | ''   | '20180511'  
 '470NH/38A'                    | 'SMLF'     | 'EMPTY'  | 'CV+47^0KZ07'(!)           = 'End of Design' | 'Comp-Release Qty' | 'CV+47^0KZ07'              |'L_HCUVD8095D-102KBQL_8X8'| 'NA'                           | 'IO'       | 'IND SMD 470NH 10% 38A(HCUVD8095D-471QL)'       | 'CHIP'         | ''          | ''   | '20180511'  
 'BLM15AG221SN1D/300MA'         | 'SMLF'     | 'IND'    | 'CX5AG221104'(!)           = ''              | ''                 | 'CX5AG221104'              |'L0402'| 'BLM15AG221SN1D/300MA'         | 'DISCRETE' | 'EMI FILTER BLM15AG221SN1D(220,300MA)'          | 'CHIP'         | ''          | ''   | '20180413'  
 'BLM15AG221SN1D/300MA'         | 'SMLF'     | 'EMPTY'  | 'CX5AG221104'(!)           = ''              | ''                 | 'CX5AG221104'              |'L0402'| 'NA'                           | 'IO'       | 'EMI FILTER BLM15AG221SN1D(220,300MA)'          | 'CHIP'         | ''          | ''   | '20180413'  
 '400NH/40A'                    | 'SMLF'     | 'IND'    | 'CV+40^0KZ02'(!)           = 'End of Design' | 'Comp-Approve'     | 'CV+40^0KZ02'              |'L_HCUVD8095D-102KBQL_8X8'| '400NH/40A'                    | 'DISCRETE' | 'IND SMD 400NH 10% 40A(HCUVD8095D-401QL)'       | 'CHIP'         | ''          | ''   | '20171012'  
 '400NH/40A'                    | 'SMLF'     | 'EMPTY'  | 'CV+40^0KZ02'(!)           = 'End of Design' | 'Comp-Approve'     | 'CV+40^0KZ02'              |'L_HCUVD8095D-102KBQL_8X8'| 'NA'                           | 'IO'       | 'IND SMD 400NH 10% 40A(HCUVD8095D-401QL)'       | 'CHIP'         | ''          | ''   | '20171012'  
 '0.56UH/36.5A'                 | 'SMLF'     | 'IND'    | 'CV+56^0KZ00'(!)           = ''              | ''                 | 'CV+56^0KZ00'              |'L_PCMB103T-2R2MS_10-1X10'| '0.56UH/36.5A'                 | 'DISCRETE' | 'IND SMD 0.56UH 10% 36.5A(CMME103T-R56MS)'      | 'CHIP'         | ''          | ''   | '20180719'  
 '0.56UH/36.5A'                 | 'SMLF'     | 'EMPTY'  | 'CV+56^0KZ00'(!)           = ''              | ''                 | 'CV+56^0KZ00'              |'L_PCMB103T-2R2MS_10-1X10'| 'NA'                           | 'IO'       | 'IND SMD 0.56UH 10% 36.5A(CMME103T-R56MS)'      | 'CHIP'         | ''          | ''   | '20180719'  
 '120NH/133A'                   | 'SMLF'     | 'IND'    | 'CV+12^0KZ10'(!)           = ''              | ''                 | 'CV+12^0KZ10'              |'L_HCUVE117512D_10-7X7-7'| '120NH/133A'                   | 'DISCRETE' | 'IND SMD 120NH 10% 133A(HCUVE117512D-121)'      | 'CHIP'         | ''          | ''   | '20180719'  
 '120NH/133A'                   | 'SMLF'     | 'EMPTY'  | 'CV+12^0KZ10'(!)           = ''              | ''                 | 'CV+12^0KZ10'              |'L_HCUVE117512D_10-7X7-7'| 'NA'                           | 'IO'       | 'IND SMD 120NH 10% 133A(HCUVE117512D-121)'      | 'CHIP'         | ''          | ''   | '20180719'  
 '68NH/300MA'                   | 'SMLF'     | 'IND'    | 'CVA6803JN12'(!)           = ''              | ''                 | 'CVA6803JN12'              |'L0603'| '68NH/300MA'                   | 'DISCRETE' | 'IND SMD 68NH +-5%300MA(LQG18HN68NJ00D)'        | 'CHIP'         | ''          | ''   | '20180719'  
 '68NH/300MA'                   | 'SMLF'     | 'EMPTY'  | 'CVA6803JN12'(!)           = ''              | ''                 | 'CVA6803JN12'              |'L0603'| 'NA'                           | 'IO'       | 'IND SMD 68NH +-5%300MA(LQG18HN68NJ00D)'        | 'CHIP'         | ''          | ''   | '20180719'  
 '10UH/20A'                     | 'SMLF'     | 'IND'    | 'CV010K0MZ00'(!)           = ''              | ''                 | 'CV010K0MZ00'              |'L_CMLB177T_16-3X17-15'| '10UH/20A'                     | 'DISCRETE' | 'IND SMD 10UH 20% 20A(CMLB177T-100MS)'          | 'CHIP'         | ''          | ''   | '20180723'  
 '10UH/20A'                     | 'SMLF'     | 'EMPTY'  | 'CV010K0MZ00'(!)           = ''              | ''                 | 'CV010K0MZ00'              |'L_CMLB177T_16-3X17-15'| 'NA'                           | 'IO'       | 'IND SMD 10UH 20% 20A(CMLB177T-100MS)'          | 'CHIP'         | ''          | ''   | '20180723'  
 '130NH/111A'                   | 'SMLF'     | 'IND'    | 'CV+13^0KZ00'(!)           = ''              | ''                 | 'CV+13^0KZ00'              |'L_HCME107512-131_10X7-5'| '130NH/111A'                   | 'DISCRETE' | 'IND SMD 130NH 10% 111A(HCME107512-131)'        | 'CHIP'         | ''          | ''   | '20180726'  
 '130NH/111A'                   | 'SMLF'     | 'EMPTY'  | 'CV+13^0KZ00'(!)           = ''              | ''                 | 'CV+13^0KZ00'              |'L_HCME107512-131_10X7-5'| 'NA'                           | 'IO'       | 'IND SMD 130NH 10% 111A(HCME107512-131)'        | 'CHIP'         | ''          | ''   | '20180726'  
 '130NH/106A'                   | 'SMLF'     | 'IND'    | 'CV+13^0KZ01'(!)           = 'End of Design' | 'Comp-Approve'     | 'CV+13^0KZ01'              |'L_HCME107512-131_10X7-5'| '130NH/106A'                   | 'DISCRETE' | 'IND SMD 130NH 10% 106A(HCME107512D-131)'       | 'CHIP'         | ''          | ''   | '20180726'  
 '130NH/106A'                   | 'SMLF'     | 'EMPTY'  | 'CV+13^0KZ01'(!)           = 'End of Design' | 'Comp-Approve'     | 'CV+13^0KZ01'              |'L_HCME107512-131_10X7-5'| 'NA'                           | 'IO'       | 'IND SMD 130NH 10% 106A(HCME107512D-131)'       | 'CHIP'         | ''          | ''   | '20180726'  
 '130NH/106A'                   | 'SMLF'     | 'IND'    | 'CV+13^0KZ03'(!)           = 'End of Design' | 'P/N Release'      | 'CV+13^0KZ03'              |'L_HCME967512D-131_9-6X7-5'| '130NH/106A'                   | 'DISCRETE' | 'IND SMD 130NH 10% 106A(HCME967512D-131)'       | 'CHIP'         | ''          | ''   | '20180726'  
 '130NH/106A'                   | 'SMLF'     | 'EMPTY'  | 'CV+13^0KZ03'(!)           = 'End of Design' | 'P/N Release'      | 'CV+13^0KZ03'              |'L_HCME967512D-131_9-6X7-5'| 'NA'                           | 'IO'       | 'IND SMD 130NH 10% 106A(HCME967512D-131)'       | 'CHIP'         | ''          | ''   | '20180726'  
 '130NH/111A'                   | 'SMLF'     | 'IND'    | 'CV+13^0KZ02'(!)           = ''              | ''                 | 'CV+13^0KZ02'              |'L_HCME967512D-131_9-6X7-5'| '130NH/111A'                   | 'DISCRETE' | 'IND SMD 130NH 10% 111A(HCME967512-131)'        | 'CHIP'         | ''          | ''   | '20180726'  
 '130NH/111A'                   | 'SMLF'     | 'EMPTY'  | 'CV+13^0KZ02'(!)           = ''              | ''                 | 'CV+13^0KZ02'              |'L_HCME967512D-131_9-6X7-5'| 'NA'                           | 'IO'       | 'IND SMD 130NH 10% 111A(HCME967512-131)'        | 'CHIP'         | ''          | ''   | '20180726'  
 '0.33UH/14A'                   | 'SMLF'     | 'IND'    | 'CV+33E0MZ00'(!)           = ''              | ''                 | 'CV+33E0MZ00'              |'L_CMME053T_4-5X4-7'| '0.33UH/14A'                   | 'DISCRETE' | 'IND SMD 0.33UH 20% 14A(CMME053T-R33MS'         | 'CHIP'         | ''          | ''   | '20180810'  
 '0.33UH/14A'                   | 'SMLF'     | 'EMPTY'  | 'CV+33E0MZ00'(!)           = ''              | ''                 | 'CV+33E0MZ00'              |'L_CMME053T_4-5X4-7'| 'NA'                           | 'IO'       | 'IND SMD 0.33UH 20% 14A(CMME053T-R33MS'         | 'CHIP'         | ''          | ''   | '20180810'  
 '0.47UH/12A'                   | 'SMLF'     | 'IND'    | 'CV+47C0MZ00'(!)           = ''              | ''                 | 'CV+47C0MZ00'              |'L_CMME053T_4-5X4-7'| '0.47UH/12A'                   | 'DISCRETE' | 'IND SMD 0.47UH 20% 12A(PCMB053T-R47MS)'        | 'CHIP'         | ''          | ''   | '20180815'  
 '0.47UH/12A'                   | 'SMLF'     | 'EMPTY'  | 'CV+47C0MZ00'(!)           = ''              | ''                 | 'CV+47C0MZ00'              |'L_CMME053T_4-5X4-7'| 'NA'                           | 'IO'       | 'IND SMD 0.47UH 20% 12A(PCMB053T-R47MS)'        | 'CHIP'         | ''          | ''   | '20180815'  
 '6.8UH/3A'                     | 'SMLF'     | 'IND'    | 'CV-6830MZ01'(!)           = ''              | ''                 | 'CV-6830MZ01'              |'L_CMME053T_4-5X4-7'| '6.8UH/3A'                     | 'DISCRETE' | 'IND SMD 6.8UH +-20% 3A PIMB053T-6R8MS'         | 'CHIP'         | ''          | ''   | '20180815'  
 '6.8UH/3A'                     | 'SMLF'     | 'EMPTY'  | 'CV-6830MZ01'(!)           = ''              | ''                 | 'CV-6830MZ01'              |'L_CMME053T_4-5X4-7'| 'NA'                           | 'IO'       | 'IND SMD 6.8UH +-20% 3A PIMB053T-6R8MS'         | 'CHIP'         | ''          | ''   | '20180815'  
 '1.5UH/3A'                     | 'SMLF'     | 'IND'    | 'CV-1530MN00'(!)           = ''              | ''                 | 'CV-1530MN00'              |'L_DFP252012TF_2-5X2'| '1.5UH/3A'                     | 'DISCRETE' | 'IND CHIP 1.5UH +-20% 3A(SRN2512-1R5M)'         | 'CHIP'         | ''          | ''   | '20180816'  
 '1.5UH/3A'                     | 'SMLF'     | 'EMPTY'  | 'CV-1530MN00'(!)           = ''              | ''                 | 'CV-1530MN00'              |'L_DFP252012TF_2-5X2'| 'NA'                           | 'IO'       | 'IND CHIP 1.5UH +-20% 3A(SRN2512-1R5M)'         | 'CHIP'         | ''          | ''   | '20180816'  
 'BK1005HS102-T/300MA'          | 'SMLF'     | 'IND'    | 'CX5HS102108'(!)           = 'End of Design' | 'End of Life'      | 'CX5HS102108'              |'L0402_EOL'| 'BK1005HS102-T/300MA'          | 'DISCRETE' | 'EMI FILTER BK1005HS102-T(1000,300MA)'          | 'CHIP'         | ''          | ''   | '20180816'  
 'BK1005HS102-T/300MA'          | 'SMLF'     | 'EMPTY'  | 'CX5HS102108'(!)           = 'End of Design' | 'End of Life'      | 'CX5HS102108'              |'L0402_EOL'| 'NA'                           | 'IO'       | 'EMI FILTER BK1005HS102-T(1000,300MA)'          | 'CHIP'         | ''          | ''   | '20180816'  
 '1UH/4.4A'                     | 'SMLF'     | 'IND'    | 'CV-1044MZ03'(!)           = ''              | ''                 | 'CV-1044MZ03'              |'L_BDHH002520101R0ME1_2-5X2'| '1UH/4.4A'                     | 'DISCRETE' | 'IND SMD 1UH,20% 4.4A(BDHH002520101R0ME1)'      | 'CHIP'         | ''          | ''   | '20180817'  
 '1UH/4.4A'                     | 'SMLF'     | 'EMPTY'  | 'CV-1044MZ03'(!)           = ''              | ''                 | 'CV-1044MZ03'              |'L_BDHH002520101R0ME1_2-5X2'| 'NA'                           | 'IO'       | 'IND SMD 1UH,20% 4.4A(BDHH002520101R0ME1)'      | 'CHIP'         | ''          | ''   | '20180817'  
 '1000H/0.22A'                  | 'SMLF'     | 'IND'    | 'CX3HR102000'(!)           = 'End of Design' | 'Comp-Approve'     | 'CX3HR102000'              |'L0201'| '1000H/0.22A'                  | 'DISCRETE' | 'EMI FILTER BEAD BK0603HR102-T(1000,0.22A'      | 'CHIP'         | ''          | ''   | '20180822'  
 '1000H/0.22A'                  | 'SMLF'     | 'EMPTY'  | 'CX3HR102000'(!)           = 'End of Design' | 'Comp-Approve'     | 'CX3HR102000'              |'L0201'| 'NA'                           | 'IO'       | 'EMI FILTER BEAD BK0603HR102-T(1000,0.22A'      | 'CHIP'         | ''          | ''   | '20180822'  
 '4.7UH/4A'                     | 'SMLF'     | 'IND'    | 'CV-4740MZ03'(!)           = ''              | ''                 | 'CV-4740MZ03'              |'L_CMME053T_4-5X4-7'| '4.7UH/4A'                     | 'DISCRETE' | 'IND SMD 4.7UH +-20% 4A(PCMB053T-4R7MS)'        | 'CHIP'         | ''          | ''   | '20180823'  
 '4.7UH/4A'                     | 'SMLF'     | 'EMPTY'  | 'CV-4740MZ03'(!)           = ''              | ''                 | 'CV-4740MZ03'              |'L_CMME053T_4-5X4-7'| 'NA'                           | 'IO'       | 'IND SMD 4.7UH +-20% 4A(PCMB053T-4R7MS)'        | 'CHIP'         | ''          | ''   | '20180823'  
 '0.68UH/8.5A'                  | 'SMLF'     | 'IND'    | 'CV+6885MZ04'(!)           = ''              | ''                 | 'CV+6885MZ04'              |'L_CMME053T_4-5X4-7'| '0.68UH/8.5A'                  | 'DISCRETE' | 'INDSMD 0.68UH +-20% 8.5A(PCMB053T-R68MS)'      | 'CHIP'         | ''          | ''   | '20180823'  
 '0.68UH/8.5A'                  | 'SMLF'     | 'EMPTY'  | 'CV+6885MZ04'(!)           = ''              | ''                 | 'CV+6885MZ04'              |'L_CMME053T_4-5X4-7'| 'NA'                           | 'IO'       | 'INDSMD 0.68UH +-20% 8.5A(PCMB053T-R68MS)'      | 'CHIP'         | ''          | ''   | '20180823'  
 '0.15UH/115A'                  | 'SMLF'     | 'IND'    | 'CV+15^0KZ17'(!)           = ''              | ''                 | 'CV+15^0KZ17'              |'L_HCUVE117512D'| '0.15UH/115A'                  | 'DISCRETE' | 'IND SMD 0.15UH 10% 115A(MSI-110812V-R15K'      | 'CHIP'         | ''          | ''   | '20180903'  
 '0.15UH/115A'                  | 'SMLF'     | 'EMPTY'  | 'CV+15^0KZ17'(!)           = ''              | ''                 | 'CV+15^0KZ17'              |'L_HCUVE117512D'| 'NA'                           | 'IO'       | 'IND SMD 0.15UH 10% 115A(MSI-110812V-R15K'      | 'CHIP'         | ''          | ''   | '20180903'  
 '150NH/119A'                   | 'SMLF'     | 'IND'    | 'CVA15^0KZ00'(!)           = ''              | ''                 | 'CVA15^0KZ00'              |'L_HCUVE117512D'| '150NH/119A'                   | 'DISCRETE' | 'IND SMD 150NH 10% 119A(HCUVE117512-151)'       | 'CHIP'         | ''          | ''   | '20180906'  
 '150NH/119A'                   | 'SMLF'     | 'EMPTY'  | 'CVA15^0KZ00'(!)           = ''              | ''                 | 'CVA15^0KZ00'              |'L_HCUVE117512D'| 'NA'                           | 'IO'       | 'IND SMD 150NH 10% 119A(HCUVE117512-151)'       | 'CHIP'         | ''          | ''   | '20180906'  
 '150NH/76A'                    | 'SMLF'     | 'IND'    | 'CV+15^0KZ19'(!)           = ''              | ''                 | 'CV+15^0KZ19'              |'L_FP1007R3_10-2X7-8'| '150NH/76A'                    | 'DISCRETE' | 'IND SMD 150NH 10% 76A(FP1007R3-R15-R)'         | 'CHIP'         | ''          | ''   | '20181002'  
 '150NH/76A'                    | 'SMLF'     | 'EMPTY'  | 'CV+15^0KZ19'(!)           = ''              | ''                 | 'CV+15^0KZ19'              |'L_FP1007R3_10-2X7-8'| 'NA'                           | 'IO'       | 'IND SMD 150NH 10% 76A(FP1007R3-R15-R)'         | 'CHIP'         | ''          | ''   | '20181002'  
 '2.2UH/5.5A'                   | 'SMLF'     | 'IND'    | 'CV-2255MZ02'(!)           = ''              | ''                 | 'CV-2255MZ02'              |'L_CMME053T_4-5X4-7'| '2.2UH/5.5A'                   | 'DISCRETE' | 'IND SMD 2.2UH +-20% 5.5A(PCMB053T-2R2MS)'      | 'CHIP'         | ''          | ''   | '20181005'  
 '2.2UH/5.5A'                   | 'SMLF'     | 'EMPTY'  | 'CV-2255MZ02'(!)           = ''              | ''                 | 'CV-2255MZ02'              |'L_CMME053T_4-5X4-7'| 'NA'                           | 'IO'       | 'IND SMD 2.2UH +-20% 5.5A(PCMB053T-2R2MS)'      | 'CHIP'         | ''          | ''   | '20181005'  
 '3.3U/5A'                      | 'SMLF'     | 'IND'    | 'CV-3350MZ11'(!)           = ''              | ''                 | 'CV-3350MZ11'              |'L_CMME053T_4-5X4-7'| '3.3U/5A'                      | 'DISCRETE' | 'IND SMD 3.3U +-20% 5A(PCMB053T-3R3MS)'         | 'CHIP'         | ''          | ''   | '20181005'  
 '3.3U/5A'                      | 'SMLF'     | 'EMPTY'  | 'CV-3350MZ11'(!)           = ''              | ''                 | 'CV-3350MZ11'              |'L_CMME053T_4-5X4-7'| 'NA'                           | 'IO'       | 'IND SMD 3.3U +-20% 5A(PCMB053T-3R3MS)'         | 'CHIP'         | ''          | ''   | '20181005'  
 '10UH/3.7A'                    | 'SMLF'     | 'IND'    | 'CV01037MZ00'(!)           = ''              | ''                 | 'CV01037MZ00'              |'L_CMME053T_4-5X4-7'| '10UH/3.7A'                    | 'DISCRETE' | 'IND SMD 10UH 20% 3.7A(CMLE053T-100MS)'         | 'CHIP'         | ''          | ''   | '20181005'  
 '10UH/3.7A'                    | 'SMLF'     | 'EMPTY'  | 'CV01037MZ00'(!)           = ''              | ''                 | 'CV01037MZ00'              |'L_CMME053T_4-5X4-7'| 'NA'                           | 'IO'       | 'IND SMD 10UH 20% 3.7A(CMLE053T-100MS)'         | 'CHIP'         | ''          | ''   | '20181005'  
 '6.8UH/4.5A'                   | 'SMLF'     | 'IND'    | 'CV-6845MZ00'(!)           = ''              | ''                 | 'CV-6845MZ00'              |'L_MMD-06CZ'| '6.8UH/4.5A'                   | 'DISCRETE' | 'IND SMD 6.8UH 20% 4.5A MMD-06CZ-6R8M-V1Q'      | 'CHIP'         | ''          | ''   | '20181011'  
 '6.8UH/4.5A'                   | 'SMLF'     | 'EMPTY'  | 'CV-6845MZ00'(!)           = ''              | ''                 | 'CV-6845MZ00'              |'L_MMD-06CZ'| 'NA'                           | 'IO'       | 'IND SMD 6.8UH 20% 4.5A MMD-06CZ-6R8M-V1Q'      | 'CHIP'         | ''          | ''   | '20181011'  
 '50NH/86A'                     | 'SMLF'     | 'IND'    | 'CVA50^0MZ07'(!)           = ''              | ''                 | 'CVA50^0MZ07'              |'L_HCBS6170_6-1X6'| '50NH/86A'                     | 'DISCRETE' | 'IND SMD 50NH 20% 86A(HCBS6170-500)'            | 'CHIP'         | ''          | ''   | '20181015'  
 '50NH/86A'                     | 'SMLF'     | 'EMPTY'  | 'CVA50^0MZ07'(!)           = ''              | ''                 | 'CVA50^0MZ07'              |'L_HCBS6170_6-1X6'| 'NA'                           | 'IO'       | 'IND SMD 50NH 20% 86A(HCBS6170-500)'            | 'CHIP'         | ''          | ''   | '20181015'  
 '130NH/99A'                    | 'SMLF'     | 'IND'    | 'CV+13^0KZ04'(!)           = ''              | ''                 | 'CV+13^0KZ04'              |'L_HCUVE768012-171_7-6X8-1'| '130NH/99A'                    | 'DISCRETE' | 'IND SMD 130NH 10% 99A(HCUVE768012-131)'        | 'CHIP'         | ''          | ''   | '20181015'  
 '130NH/99A'                    | 'SMLF'     | 'EMPTY'  | 'CV+13^0KZ04'(!)           = ''              | ''                 | 'CV+13^0KZ04'              |'L_HCUVE768012-171_7-6X8-1'| 'NA'                           | 'IO'       | 'IND SMD 130NH 10% 99A(HCUVE768012-131)'        | 'CHIP'         | ''          | ''   | '20181015'  
 '130NH/95A'                    | 'SMLF'     | 'IND'    | 'CV+13^0KZ05'(!)           = 'End of Design' | 'Comp-Approve'     | 'CV+13^0KZ05'              |'L_HCUVE768012-171_7-6X8-1'| '130NH/95A'                    | 'DISCRETE' | 'IND SMD 130NH 10% 95A(HCUVE768012D-131)'       | 'CHIP'         | ''          | ''   | '20181015'  
 '130NH/95A'                    | 'SMLF'     | 'EMPTY'  | 'CV+13^0KZ05'(!)           = 'End of Design' | 'Comp-Approve'     | 'CV+13^0KZ05'              |'L_HCUVE768012-171_7-6X8-1'| 'NA'                           | 'IO'       | 'IND SMD 130NH 10% 95A(HCUVE768012D-131)'       | 'CHIP'         | ''          | ''   | '20181015'  
 '1.5UH/26A'                    | 'SMLF'     | 'IND'    | 'CV-15R0MZ00'(!)           = ''              | ''                 | 'CV-15R0MZ00'              |'L_PCMS136E_13-45X12-6'| '1.5UH/26A'                    | 'DISCRETE' | 'IND SMD 1.5UH +-20% 26A PCMS136E-1R5MF'        | 'CHIP'         | ''          | ''   | '20181025'  
 '1.5UH/26A'                    | 'SMLF'     | 'EMPTY'  | 'CV-15R0MZ00'(!)           = ''              | ''                 | 'CV-15R0MZ00'              |'L_PCMS136E_13-45X12-6'| 'NA'                           | 'IO'       | 'IND SMD 1.5UH +-20% 26A PCMS136E-1R5MF'        | 'CHIP'         | ''          | ''   | '20181025'  
 'FBMH2012HM331-T/1.8A'         | 'SMLF'     | 'IND'    | 'CX000331000'(!)           = 'End of Design' | 'Comp-Approve'     | 'CX000331000'              |'L0805'| 'FBMH2012HM331-T/1.8A'         | 'DISCRETE' | 'FILTER CHIP FBMH2012HM331 330,1.8A'            | 'CHIP'         | ''          | ''   | '20181026'  
 'FBMH2012HM331-T/1.8A'         | 'SMLF'     | 'EMPTY'  | 'CX000331000'(!)           = 'End of Design' | 'Comp-Approve'     | 'CX000331000'              |'L0805'| 'NA'                           | 'IO'       | 'FILTER CHIP FBMH2012HM331 330,1.8A'            | 'CHIP'         | ''          | ''   | '20181026'  
 '56NH/94A'                     | 'SMLF'     | 'IND'    | 'CVA56^0KZ00'(!)           = ''              | ''                 | 'CVA56^0KZ00'              |'L_TPI078060L056N_7X8'| '56NH/94A'                     | 'DISCRETE' | 'IND SMD 56NH 10% 94A(TPI078060L056N)'          | 'CHIP'         | ''          | ''   | '20181101'  
 '56NH/94A'                     | 'SMLF'     | 'EMPTY'  | 'CVA56^0KZ00'(!)           = ''              | ''                 | 'CVA56^0KZ00'              |'L_TPI078060L056N_7X8'| 'NA'                           | 'IO'       | 'IND SMD 56NH 10% 94A(TPI078060L056N)'          | 'CHIP'         | ''          | ''   | '20181101'  
 'BLM18EG221SN1D/2A'            | 'SMLF'     | 'IND'    | 'CX8EG221011'(!)           = 'End of Design' | 'Comp-Approve'     | 'CX8EG221011'              |'L0603'| 'BLM18EG221SN1D/2A'            | 'DISCRETE' | 'EMI FILTER BLM18EG221SN1D(220,2A)'             | 'CHIP'         | ''          | ''   | '20111228'  
 'BLM18EG221SN1D/2A'            | 'SMLF'     | 'EMPTY'  | 'CX8EG221011'(!)           = 'End of Design' | 'Comp-Approve'     | 'CX8EG221011'              |'L0603'| 'NA'                           | 'IO'       | 'EMI FILTER BLM18EG221SN1D(220,2A)'             | 'CHIP'         | ''          | ''   | '20111228'  
 'GMLB-160808-0600L-N8A/0.5A'   | 'SMLF'     | 'IND'    | 'CX080600003'(!)           = ''              | ''                 | 'CX080600003'              |'L0603'| 'GMLB-160808-0600L-N8A/0.5A'   | 'DISCRETE' | 'EMI FILT GMLB-160808-0600L-N8A(600,0.5A)'      | 'CHIP'         | ''          | ''   | '20181218'  
 'GMLB-160808-0600L-N8A/0.5A'   | 'SMLF'     | 'EMPTY'  | 'CX080600003'(!)           = ''              | ''                 | 'CX080600003'              |'L0603'| 'NA'                           | 'IO'       | 'EMI FILT GMLB-160808-0600L-N8A(600,0.5A)'      | 'CHIP'         | ''          | ''   | '20181218'  
 '0.15UH/35A'                   | 'SMLF'     | 'IND'    | 'CV+15^0MZ37'(!)           = ''              | ''                 | 'CV+15^0MZ37'              |'L_MMD-10BZNR15M-M1Q_11-5X10'| '0.15UH/35A'                   | 'DISCRETE' | 'IND SMD 0.15U 20% 35A(MMD-10BZNR15M-M1Q)'      | 'CHIP'         | ''          | ''   | '20181219'  
 '0.15UH/35A'                   | 'SMLF'     | 'EMPTY'  | 'CV+15^0MZ37'(!)           = ''              | ''                 | 'CV+15^0MZ37'              |'L_MMD-10BZNR15M-M1Q_11-5X10'| 'NA'                           | 'IO'       | 'IND SMD 0.15U 20% 35A(MMD-10BZNR15M-M1Q)'      | 'CHIP'         | ''          | ''   | '20181219'  
 '0.15U/27A'                    | 'SMLF'     | 'IND'    | 'CV+15S0MZ02'(!)           = ''              | ''                 | 'CV+15S0MZ02'              |'L_MMD-05BZ_5-49X5-18'| '0.15U/27A'                    | 'DISCRETE' | 'IND SMD 0.15U 20% 27A(MMD-05BZ-R15M-R1Q)'      | 'CHIP'         | ''          | ''   | '20190103'  
 '0.15U/27A'                    | 'SMLF'     | 'EMPTY'  | 'CV+15S0MZ02'(!)           = ''              | ''                 | 'CV+15S0MZ02'              |'L_MMD-05BZ_5-49X5-18'| 'NA'                           | 'IO'       | 'IND SMD 0.15U 20% 27A(MMD-05BZ-R15M-R1Q)'      | 'CHIP'         | ''          | ''   | '20190103'  
 'HCB1608KF-601T20/2A'          | 'SMLF'     | 'IND'    | 'CX601T20001'(!)           = ''              | ''                 | 'CX601T20001'              |'L0603'| 'HCB1608KF-601T20/2A'          | 'DISCRETE' | 'EMI FILTER CHIP HCB1608KF-601T20(600,2A)'      | 'CHIP'         | ''          | ''   | '20190110'  
 'HCB1608KF-601T20/2A'          | 'SMLF'     | 'EMPTY'  | 'CX601T20001'(!)           = ''              | ''                 | 'CX601T20001'              |'L0603'| 'NA'                           | 'IO'       | 'EMI FILTER CHIP HCB1608KF-601T20(600,2A)'      | 'CHIP'         | ''          | ''   | '20190110'  
 '1UH/4.2A'                     | 'SMLF'     | 'IND'    | 'CV-1042MZ11'(!)           = ''              | ''                 | 'CV-1042MZ11'              |'L_MLV-YT12N_2-5X2'| '1UH/4.2A'                     | 'DISCRETE' | 'IND SMD 1UH 20% 4.2A(MLV-YT12N1R0M-C2Q)'       | 'CHIP'         | ''          | ''   | '20190125'  
 '1UH/4.2A'                     | 'SMLF'     | 'EMPTY'  | 'CV-1042MZ11'(!)           = ''              | ''                 | 'CV-1042MZ11'              |'L_MLV-YT12N_2-5X2'| 'NA'                           | 'IO'       | 'IND SMD 1UH 20% 4.2A(MLV-YT12N1R0M-C2Q)'       | 'CHIP'         | ''          | ''   | '20190125'  
 'BLM15PD800SN1D/1000A'         | 'SMLF'     | 'IND'    | 'CX5PD800000'(!)           = ''              | ''                 | 'CX5PD800000'              |'L0402'| 'BLM15PD800SN1D'               | 'DISCRETE' | 'EMI FILTER BLM15PD800SN1D(80,1000MA)'          | 'CHIP'         | ''          | ''   | '20190130'  
 'BLM15PD800SN1D/1000A'         | 'SMLF'     | 'EMPTY'  | 'CX5PD800000'(!)           = ''              | ''                 | 'CX5PD800000'              |'L0402'| 'NA'                           | 'IO'       | 'EMI FILTER BLM15PD800SN1D(80,1000MA)'          | 'CHIP'         | ''          | ''   | '20190130'  
 'BK1005HS800-T/0.7A'           | 'SMLF'     | 'IND'    | 'CX5HS800000'(!)           = 'End of Design' | 'Comp-Release Qty' | 'CX5HS800000'              |'L0402'| 'BK1005HS800-T'                | 'DISCRETE' | 'EMI FILTER BK1005HS800-T(80,0.7A)'             | 'CHIP'         | ''          | ''   | '20190130'  
 'BK1005HS800-T/0.7A'           | 'SMLF'     | 'EMPTY'  | 'CX5HS800000'(!)           = 'End of Design' | 'Comp-Release Qty' | 'CX5HS800000'              |'L0402'| 'NA'                           | 'IO'       | 'EMI FILTER BK1005HS800-T(80,0.7A)'             | 'CHIP'         | ''          | ''   | '20190130'  
 '0.4UH/25A'                    | 'SMLF'     | 'IND'    | 'CV+04Q0KZ00'(!)           = ''              | ''                 | 'CV+04Q0KZ00'              |'L_FP1107R2-R40-R'| '0.4UH/25A'                    | 'DISCRETE' | 'IND SMD 0.4UH 10% 25A(FP1107R2-R40-R)'         | 'CHIP'         | ''          | ''   | '20190215'  
 '0.4UH/25A'                    | 'SMLF'     | 'EMPTY'  | 'CV+04Q0KZ00'(!)           = ''              | ''                 | 'CV+04Q0KZ00'              |'L_FP1107R2-R40-R'| 'NA'                           | 'IO'       | 'IND SMD 0.4UH 10% 25A(FP1107R2-R40-R)'         | 'CHIP'         | ''          | ''   | '20190215'  
 'HCB1608KF-600T30/3A'          | 'SMLF'     | 'IND'    | 'CX600T30000'(!)           = ''              | ''                 | 'CX600T30000'              |'L0603'| 'HCB1608KF-600T30/3A'          | 'DISCRETE' | 'EMI FILTER HCB1608KF-600T30(60,3A)'            | 'CHIP'         | ''          | ''   | '20190220'  
 'HCB1608KF-600T30/3A'          | 'SMLF'     | 'EMPTY'  | 'CX600T30000'(!)           = ''              | ''                 | 'CX600T30000'              |'L0603'| 'NA'                           | 'IO'       | 'EMI FILTER HCB1608KF-600T30(60,3A)'            | 'CHIP'         | ''          | ''   | '20190220'  
 '220NH/61A'                    | 'SMLF'     | 'IND'    | 'CV+22^0KZ19'(!)           = 'End of Design' | 'Comp-Approve'     | 'CV+22^0KZ19'              |'L_HCUVE966412D-221'| '220NH/61A'                    | 'DISCRETE' | 'IND SMD 220NH 10% 61A(HCUVE966412D-221)'       | 'CHIP'         | ''          | ''   | '20160727'  
 '220NH/61A'                    | 'SMLF'     | 'EMPTY'  | 'CV+22^0KZ19'(!)           = 'End of Design' | 'Comp-Approve'     | 'CV+22^0KZ19'              |'L_HCUVE966412D-221'| 'NA'                           | 'IO'       | 'IND SMD 220NH 10% 61A(HCUVE966412D-221)'       | 'CHIP'         | ''          | ''   | '20160727'  
 '82NH/10A'                     | 'SMLF'     | 'IND'    | 'CVA82A0MZ00'(!)           = ''              | ''                 | 'CVA82A0MZ00'              |'L_MSI-400403_4-5X4-5'| '82NH/10A'                     | 'DISCRETE' | 'IND SMD 82NH 20% 10A(MSI-400403-82NM'          | 'CHIP'         | ''          | ''   | '20190320'  
 '82NH/10A'                     | 'SMLF'     | 'EMPTY'  | 'CVA82A0MZ00'(!)           = ''              | ''                 | 'CVA82A0MZ00'              |'L_MSI-400403_4-5X4-5'| 'NA'                           | 'IO'       | 'IND SMD 82NH 20% 10A(MSI-400403-82NM'          | 'CHIP'         | ''          | ''   | '20190320'  
 '0.1UH/20A'                    | 'SMLF'     | 'IND'    | 'CV+10K0MZ00'(!)           = ''              | ''                 | 'CV+10K0MZ00'              |'L_MSI-600603_6-5X6'| '0.1UH/20A'                    | 'DISCRETE' | 'IND SMD 0.1UH 20% 20A(MSI-600603-R10M'         | 'CHIP'         | ''          | ''   | '20190320'  
 '0.1UH/20A'                    | 'SMLF'     | 'EMPTY'  | 'CV+10K0MZ00'(!)           = ''              | ''                 | 'CV+10K0MZ00'              |'L_MSI-600603_6-5X6'| 'NA'                           | 'IO'       | 'IND SMD 0.1UH 20% 20A(MSI-600603-R10M'         | 'CHIP'         | ''          | ''   | '20190320'  
 '1UH/9.2A'                     | 'SMLF'     | 'IND'    | 'CV-1092MZ01'(!)           = ''              | ''                 | 'CV-1092MZ01'              |'L_MMD-05CZ-3R3M-M2Q'| '1UH/9.2A'                     | 'DISCRETE' | 'IND SMD 1UH 20% 9.2A(MMD-05CZ-1R0M-V7Q)'       | 'CHIP'         | ''          | ''   | '20190329'  
 '1UH/9.2A'                     | 'SMLF'     | 'EMPTY'  | 'CV-1092MZ01'(!)           = ''              | ''                 | 'CV-1092MZ01'              |'L_MMD-05CZ-3R3M-M2Q'| 'NA'                           | 'IO'       | 'IND SMD 1UH 20% 9.2A(MMD-05CZ-1R0M-V7Q)'       | 'CHIP'         | ''          | ''   | '20190329'  
 '47NH/90A'                     | 'SMLF'     | 'IND'    | 'CVA47^0KZ00'(!)           = ''              | ''                 | 'CVA47^0KZ00'              |'L_TPI078060L056N_7X8'| '47NH/90A'                     | 'DISCRETE' | 'IND SMD 47NH 10% 90A(TPI078060L047N)'          | 'CHIP'         | ''          | ''   | '20190410'  
 '47NH/90A'                     | 'SMLF'     | 'EMPTY'  | 'CVA47^0KZ00'(!)           = ''              | ''                 | 'CVA47^0KZ00'              |'L_TPI078060L056N_7X8'| 'NA'                           | 'IO'       | 'IND SMD 47NH 10% 90A(TPI078060L047N)'          | 'CHIP'         | ''          | ''   | '20190410'  
 '900NH/47A'                    | 'SMLF'     | 'IND'    | 'CV+90^0KZ00'(!)           = ''              | ''                 | 'CV+90^0KZ00'              |'L_HCUVD1115_11X8XA'| '900NH/47A'                    | 'DISCRETE' | 'IND SMD 900NH 10% 47A(HCUVD1115-901QL)'        | 'CHIP'         | ''          | ''   | '20190424'  
 '900NH/47A'                    | 'SMLF'     | 'EMPTY'  | 'CV+90^0KZ00'(!)           = ''              | ''                 | 'CV+90^0KZ00'              |'L_HCUVD1115_11X8XA'| 'NA'                           | 'IO'       | 'IND SMD 900NH 10% 47A(HCUVD1115-901QL)'        | 'CHIP'         | ''          | ''   | '20190424'  
 'MHC3216S121WBE/6A'            | 'SMLF'     | 'IND'    | 'CX16S121001'(!)           = ''              | ''                 | 'CX16S121001'              |'L1206XC'| 'MHC3216S121WBE/6A'            | 'DISCRETE' | 'EMI FILTER BEAD MHC3216S121WBE(120,6A)'        | 'CHIP'         | ''          | ''   | '20190429'  
 'MHC3216S121WBE/6A'            | 'SMLF'     | 'EMPTY'  | 'CX16S121001'(!)           = ''              | ''                 | 'CX16S121001'              |'L1206XC'| 'NA'                           | 'IO'       | 'EMI FILTER BEAD MHC3216S121WBE(120,6A)'        | 'CHIP'         | ''          | ''   | '20190429'  
 '50N/86A'                      | 'SMLF'     | 'IND'    | 'CVA50^0MZ08'(!)           = ''              | ''                 | 'CVA50^0MZ08'              |'L_HCBS6170_6-1X6'| '50N/86A'                      | 'DISCRETE' | 'IND SMD 50N 20% 86A(MSI-600607-50NM-E-QU'      | 'CHIP'         | ''          | ''   | '20190426'  
 '50N/86A'                      | 'SMLF'     | 'EMPTY'  | 'CVA50^0MZ08'(!)           = ''              | ''                 | 'CVA50^0MZ08'              |'L_HCBS6170_6-1X6'| 'NA'                           | 'IO'       | 'IND SMD 50N 20% 86A(MSI-600607-50NM-E-QU'      | 'CHIP'         | ''          | ''   | '20190426'  
 '100NH/95A'                    | 'SMLF'     | 'IND'    | 'CV+10^0KZ04'(!)           = ''              | ''                 | 'CV+10^0KZ04'              |'L_AH3740A-100K_9-5X6-4'| '100NH/95A'                    | 'DISCRETE' | 'IND SMD 100NH 10% 95A(AH3740A-100K)'           | 'CHIP'         | ''          | ''   | '20190521'  
 '100NH/95A'                    | 'SMLF'     | 'EMPTY'  | 'CV+10^0KZ04'(!)           = ''              | ''                 | 'CV+10^0KZ04'              |'L_AH3740A-100K_9-5X6-4'| 'NA'                           | 'IO'       | 'IND SMD 100NH 10% 95A(AH3740A-100K)'           | 'CHIP'         | ''          | ''   | '20190521'  
 '10UH/200MA'                   | 'SMLF'     | 'IND'    | 'CV01002MN10'(!)           = ''              | ''                 | 'CV01002MN10'              |'L0805_H62'| '10UH/200MA'                   | 'DISCRETE' | 'IND CHIP 10UH +-20% 200MA(MLZ2012M100HT)'      | 'CHIP'         | ''          | ''   | '20190603'  
 '10UH/200MA'                   | 'SMLF'     | 'EMPTY'  | 'CV01002MN10'(!)           = ''              | ''                 | 'CV01002MN10'              |'L0805_H62'| 'NA'                           | 'IO'       | 'IND CHIP 10UH +-20% 200MA(MLZ2012M100HT)'      | 'CHIP'         | ''          | ''   | '20190603'  
 '4.7UH/48A'                    | 'SMLF'     | 'IND'    | 'CV-47^0KZ02'(!)           = ''              | ''                 | 'CV-47^0KZ02'              |'L_SER2814H_27-9X19-3'| '4.7UH/48A'                    | 'DISCRETE' | 'IND SMD 4.7UH 10% 48A(SER2814H-472KL)'         | 'CHIP'         | ''          | ''   | '20190604'  
 '4.7UH/48A'                    | 'SMLF'     | 'EMPTY'  | 'CV-47^0KZ02'(!)           = ''              | ''                 | 'CV-47^0KZ02'              |'L_SER2814H_27-9X19-3'| 'NA'                           | 'IO'       | 'IND SMD 4.7UH 10% 48A(SER2814H-472KL)'         | 'CHIP'         | ''          | ''   | '20190604'  
 '55N/63A'                      | 'SMLF'     | 'IND'    | 'CVA55^0TZ00'(!)           = ''              | ''                 | 'CVA55^0TZ00'              |'L_SL2218A_5-35X5-7'| '55N/63A'                      | 'DISCRETE' | 'IND SMD 55N 15% 63A(SL2218A-R055LHF)'          | 'CHIP'         | ''          | ''   | '20190606'  
 '55N/63A'                      | 'SMLF'     | 'EMPTY'  | 'CVA55^0TZ00'(!)           = ''              | ''                 | 'CVA55^0TZ00'              |'L_SL2218A_5-35X5-7'| 'NA'                           | 'IO'       | 'IND SMD 55N 15% 63A(SL2218A-R055LHF)'          | 'CHIP'         | ''          | ''   | '20190606'  
 '0.82UH/31A'                   | 'SMLF'     | 'IND'    | 'CV+82W0MZ01'(!)           = ''              | ''                 | 'CV+82W0MZ01'              |'L_PCMC135T'| '0.82UH/31A'                   | 'DISCRETE' | 'IND SMD 0.82UH +-20%31A(PCMC135T-R82)'         | 'CHIP'         | ''          | ''   | '20190709'  
 '0.82UH/31A'                   | 'SMLF'     | 'EMPTY'  | 'CV+82W0MZ01'(!)           = ''              | ''                 | 'CV+82W0MZ01'              |'L_PCMC135T'| 'NA'                           | 'IO'       | 'IND SMD 0.82UH +-20%31A(PCMC135T-R82)'         | 'CHIP'         | ''          | ''   | '20190709'  
 '0.33UH/13.5A'                 | 'SMLF'     | 'IND'    | 'CV+33D5MZ00'(!)           = ''              | ''                 | 'CV+33D5MZ00'              |'L_MMD-06AEE_6-86X6-47'| '0.33UH/13.5A'                 | 'DISCRETE' | 'IND SMD 0.33UH20%13.5A,(CMME061E-R33MS)'       | 'CHIP'         | ''          | ''   | '20190716'  
 '0.33UH/13.5A'                 | 'SMLF'     | 'EMPTY'  | 'CV+33D5MZ00'(!)           = ''              | ''                 | 'CV+33D5MZ00'              |'L_MMD-06AEE_6-86X6-47'| 'NA'                           | 'IO'       | 'IND SMD 0.33UH20%13.5A,(CMME061E-R33MS)'       | 'CHIP'         | ''          | ''   | '20190716'  
 '1.0UH/13.5A'                  | 'SMLF'     | 'IND'    | 'CV-10D5MZ00'(!)           = ''              | ''                 | 'CV-10D5MZ00'              |'L_VCMT063T-2R2MN5'| '1.0UH/13.5A'                  | 'DISCRETE' | 'IND SMD 1.0U +-20% 13.5A(PCME063T-1R0MS)'      | 'CHIP'         | ''          | ''   | '20190726'  
 '1.0UH/13.5A'                  | 'SMLF'     | 'EMPTY'  | 'CV-10D5MZ00'(!)           = ''              | ''                 | 'CV-10D5MZ00'              |'L_VCMT063T-2R2MN5'| 'NA'                           | 'IO'       | 'IND SMD 1.0U +-20% 13.5A(PCME063T-1R0MS)'      | 'CHIP'         | ''          | ''   | '20190726'  
 '4UH/40A'                      | 'SMLF'     | 'IND'    | 'CV-40^0TZ00'(!)           = 'Non-Preferred' | 'End of Life'      | 'CV-40^0TZ00'              |'LC_61126_EOL'| '4UH/40A'                      | 'DISCRETE' | 'IND SMD 4UH +15/-30% 40A(61126)'               | 'CHIP'         | ''          | ''   | '20190724'  
 '4UH/40A'                      | 'SMLF'     | 'EMPTY'  | 'CV-40^0TZ00'(!)           = 'Non-Preferred' | 'End of Life'      | 'CV-40^0TZ00'              |'LC_61126_EOL'| 'NA'                           | 'IO'       | 'IND SMD 4UH +15/-30% 40A(61126)'               | 'CHIP'         | ''          | ''   | '20190724'  
 '220NH/61A'                    | 'SMLF'     | 'IND'    | 'CV122^0KZ01'(!)           = 'End of Design' | 'Comp-Release Qty' | 'CV122^0KZ01'              |'L_HCUVE966412D-221'| '220NH/61A'                    | 'DISCRETE' | 'IND SMD 220NH 10% 61A(HCUVE9612D-221QL)'       | 'CHIP'         | ''          | ''   | '20190807'  
 '220NH/61A'                    | 'SMLF'     | 'EMPTY'  | 'CV122^0KZ01'(!)           = 'End of Design' | 'Comp-Release Qty' | 'CV122^0KZ01'              |'L_HCUVE966412D-221'| 'NA'                           | 'IO'       | 'IND SMD 220NH 10% 61A(HCUVE9612D-221QL)'       | 'CHIP'         | ''          | ''   | '20190807'  
 '1UH/17.5A'                    | 'SMLF'     | 'IND'    | 'CV-1018MZ09'(!)           = ''              | ''                 | 'CV-1018MZ09'              |'L_CMML065T_6-6X6-6'| '1UH/17.5A'                    | 'DISCRETE' | 'IND SMD 1UH20%17.5A(CMML065T-1R0ME3R607)'      | 'CHIP'         | ''          | ''   | '20190808'  
 '1UH/17.5A'                    | 'SMLF'     | 'EMPTY'  | 'CV-1018MZ09'(!)           = ''              | ''                 | 'CV-1018MZ09'              |'L_CMML065T_6-6X6-6'| 'NA'                           | 'IO'       | 'IND SMD 1UH20%17.5A(CMML065T-1R0ME3R607)'      | 'CHIP'         | ''          | ''   | '20190808'  
 '1UH/14.5A'                    | 'SMLF'     | 'IND'    | 'CV-10E5MZ02'(!)           = ''              | ''                 | 'CV-10E5MZ02'              |'L_VCMT063T-2R2MN5_H158'| '1UH/14.5A'                    | 'DISCRETE' | 'IND SMD 1UH 20%14.5A,CMME064T-1R0MS'           | 'CHIP'         | ''          | ''   | '20190814'  
 '1UH/14.5A'                    | 'SMLF'     | 'EMPTY'  | 'CV-10E5MZ02'(!)           = ''              | ''                 | 'CV-10E5MZ02'              |'L_VCMT063T-2R2MN5_H158'| 'NA'                           | 'IO'       | 'IND SMD 1UH 20%14.5A,CMME064T-1R0MS'           | 'CHIP'         | ''          | ''   | '20190814'  
 '1UH/7A'                       | 'SMLF'     | 'IND'    | 'CV-1070MZ12'(!)           = ''              | ''                 | 'CV-1070MZ12'              |'L_MMD-05CZ-2R2M-X2Q'| '1UH/7A'                       | 'DISCRETE' | 'IND SMD 1UH+-20%7A(MMD-05CZ-1R0M-X7Q)'         | 'CHIP'         | ''          | ''   | '20190819'  
 '1UH/7A'                       | 'SMLF'     | 'EMPTY'  | 'CV-1070MZ12'(!)           = ''              | ''                 | 'CV-1070MZ12'              |'L_MMD-05CZ-2R2M-X2Q'| 'NA'                           | 'IO'       | 'IND SMD 1UH+-20%7A(MMD-05CZ-1R0M-X7Q)'         | 'CHIP'         | ''          | ''   | '20190819'  
 '4UH/45A'                      | 'SMLF'     | 'IND'    | 'CV-40^0TZ01'(!)           = 'Non-Preferred' | 'End of Life'      | 'CV-40^0TZ01'              |'LC_61126_EOL'| '4UH/45A'                      | 'DISCRETE' | 'IND SMD 4UH +15/-30% 45A(61126R02)'            | 'CHIP'         | ''          | ''   | '20190827'  
 '4UH/45A'                      | 'SMLF'     | 'EMPTY'  | 'CV-40^0TZ01'(!)           = 'Non-Preferred' | 'End of Life'      | 'CV-40^0TZ01'              |'LC_61126_EOL'| 'NA'                           | 'IO'       | 'IND SMD 4UH +15/-30% 45A(61126R02)'            | 'CHIP'         | ''          | ''   | '20190827'  
 'BLM31PG121SN1L/3A'            | 'SMLF'     | 'IND'    | 'CX1PG121006'(!)           = 'End of Design' | 'Comp-Approve'     | 'CX1PG121006'              |'L1206XD'| 'BLM31PG121SN1L/3A'            | 'DISCRETE' | 'EMI CHIP BLM31PG121SN1L(120,3A)'               | 'CHIP'         | ''          | ''   | '20190902'  
 'BLM31PG121SN1L/3A'            | 'SMLF'     | 'EMPTY'  | 'CX1PG121006'(!)           = 'End of Design' | 'Comp-Approve'     | 'CX1PG121006'              |'L1206XD'| 'NA'                           | 'IO'       | 'EMI CHIP BLM31PG121SN1L(120,3A)'               | 'CHIP'         | ''          | ''   | '20190902'  
 '1UH/16A'                      | 'SMLF'     | 'IND'    | 'CV-10G0MZ02'(!)           = ''              | ''                 | 'CV-10G0MZ02'              |'L_MMD-06DZ'| '1UH/16A'                      | 'DISCRETE' | 'IND SMD 1UH 20%16A,MMD-06DZE1R0M-M1Q'          | 'CHIP'         | ''          | ''   | '20190906'  
 '1UH/16A'                      | 'SMLF'     | 'EMPTY'  | 'CV-10G0MZ02'(!)           = ''              | ''                 | 'CV-10G0MZ02'              |'L_MMD-06DZ'| 'NA'                           | 'IO'       | 'IND SMD 1UH 20%16A,MMD-06DZE1R0M-M1Q'          | 'CHIP'         | ''          | ''   | '20190906'  
 '130NH/106A'                   | 'SMLF'     | 'IND'    | 'CV+13^0KZ08'(!)           = ''              | ''                 | 'CV+13^0KZ08'              |'L_HCME107512-131_10X7-5'| '130NH/106A'                   | 'DISCRETE' | 'IND SMD 130NH 10% 106A(HCME107512Q-131QL'      | 'CHIP'         | ''          | ''   | '20190909'  
 '130NH/106A'                   | 'SMLF'     | 'EMPTY'  | 'CV+13^0KZ08'(!)           = ''              | ''                 | 'CV+13^0KZ08'              |'L_HCME107512-131_10X7-5'| 'NA'                           | 'IO'       | 'IND SMD 130NH 10% 106A(HCME107512Q-131QL'      | 'CHIP'         | ''          | ''   | '20190909'  
 '130NH/95A'                    | 'SMLF'     | 'IND'    | 'CV+13^0KZ09'(!)           = ''              | ''                 | 'CV+13^0KZ09'              |'L_HCUVE768012-171_7-6X8-1'| '130NH/95A'                    | 'DISCRETE' | 'IND SMD 130NH 10% 95A(HCUVE768012Q-131QL'      | 'CHIP'         | ''          | ''   | '20190909'  
 '130NH/95A'                    | 'SMLF'     | 'EMPTY'  | 'CV+13^0KZ09'(!)           = ''              | ''                 | 'CV+13^0KZ09'              |'L_HCUVE768012-171_7-6X8-1'| 'NA'                           | 'IO'       | 'IND SMD 130NH 10% 95A(HCUVE768012Q-131QL'      | 'CHIP'         | ''          | ''   | '20190909'  
 '3.7UH/45A'                    | 'SMLF'     | 'IND'    | 'CV-37^0TZ00'(!)           = 'Non-Preferred' | 'End of Life'      | 'CV-37^0TZ00'              |'LC_61126_H504_EOL'| '3.7UH/45A'                    | 'DISCRETE' | 'IND SMD 3.7UH +15/-30% 45A(61126R03)'          | 'CHIP'         | ''          | ''   | '20190918'  
 '3.7UH/45A'                    | 'SMLF'     | 'EMPTY'  | 'CV-37^0TZ00'(!)           = 'Non-Preferred' | 'End of Life'      | 'CV-37^0TZ00'              |'LC_61126_H504_EOL'| 'NA'                           | 'IO'       | 'IND SMD 3.7UH +15/-30% 45A(61126R03)'          | 'CHIP'         | ''          | ''   | '20190918'  
 'BLM41PG471SN1L/2A'            | 'SMLF'     | 'IND'    | 'CX41PG47000'(!)           = ''              | ''                 | 'CX41PG47000'              |'L1806XA'| 'BLM41PG471SN1L/2A'            | 'DISCRETE' | 'EMI FILTER CHIP BLM41PG471SN1L(470,2A)'        | 'CHIP'         | ''          | ''   | '20191002'  
 'BLM41PG471SN1L/2A'            | 'SMLF'     | 'EMPTY'  | 'CX41PG47000'(!)           = ''              | ''                 | 'CX41PG47000'              |'L1806XA'| 'NA'                           | 'IO'       | 'EMI FILTER CHIP BLM41PG471SN1L(470,2A)'        | 'CHIP'         | ''          | ''   | '20191002'  
 '1UH/18A'                      | 'SMLF'     | 'IND'    | 'CV-10I0MZ14'(!)           = ''              | ''                 | 'CV-10I0MZ14'              |'L_VCMT063T-2R2MN5_H158'| '1UH/18A'                      | 'DISCRETE' | 'IND SMD 1UH 20% 18A(CMLE064T-1R0MS)'           | 'CHIP'         | ''          | ''   | '20191002'  
 '1UH/18A'                      | 'SMLF'     | 'EMPTY'  | 'CV-10I0MZ14'(!)           = ''              | ''                 | 'CV-10I0MZ14'              |'L_VCMT063T-2R2MN5_H158'| 'NA'                           | 'IO'       | 'IND SMD 1UH 20% 18A(CMLE064T-1R0MS)'           | 'CHIP'         | ''          | ''   | '20191002'  
 'MPZ1608S221ATD25/2.2A'        | 'SMLF'     | 'IND'    | 'CXS221AT000'(!)           = ''              | ''                 | 'CXS221AT000'              |'L0603'| 'MPZ1608S221ATD25/2.2A'        | 'DISCRETE' | 'EMI FILTER MPZ1608S221ATD25 (220,2.2A)'        | 'CHIP'         | ''          | ''   | '20191030'  
 'MPZ1608S221ATD25/2.2A'        | 'SMLF'     | 'EMPTY'  | 'CXS221AT000'(!)           = ''              | ''                 | 'CXS221AT000'              |'L0603'| 'NA'                           | 'IO'       | 'EMI FILTER MPZ1608S221ATD25 (220,2.2A)'        | 'CHIP'         | ''          | ''   | '20191030'  
 'HCB2012KF-331T30/3A'          | 'SMLF'     | 'IND'    | 'CX002012001'(!)           = ''              | ''                 | 'CX002012001'              |'L0805'| 'HCB2012KF-331T30/3A'          | 'DISCRETE' | 'EMI FILTER BEAD HCB2012KF-331T30(330,3A)'      | 'CHIP'         | ''          | ''   | '20191115'  
 'HCB2012KF-331T30/3A'          | 'SMLF'     | 'EMPTY'  | 'CX002012001'(!)           = ''              | ''                 | 'CX002012001'              |'L0805'| 'NA'                           | 'IO'       | 'EMI FILTER BEAD HCB2012KF-331T30(330,3A)'      | 'CHIP'         | ''          | ''   | '20191115'  
 'HCB2012VF-331T15/1.5A'        | 'SMLF'     | 'IND'    | 'CX331T15000'(!)           = ''              | ''                 | 'CX331T15000'              |'L0805'| 'HCB2012VF-331T15/1.5A'        | 'DISCRETE' | 'EMI FILTER HCB2012VF-331T15(330,1.5A)'         | 'CHIP'         | ''          | ''   | '20191121'  
 'HCB2012VF-331T15/1.5A'        | 'SMLF'     | 'EMPTY'  | 'CX331T15000'(!)           = ''              | ''                 | 'CX331T15000'              |'L0805'| 'NA'                           | 'IO'       | 'EMI FILTER HCB2012VF-331T15(330,1.5A)'         | 'CHIP'         | ''          | ''   | '20191121'  
 'HCB2012KF-220T60/6A'          | 'SMLF'     | 'IND'    | 'CX000220011'(!)           = ''              | ''                 | 'CX000220011'              |'L0805'| 'HCB2012KF-220T60/6A'          | 'DISCRETE' | 'EMI FILTER CHIP HCB2012KF220T60(22 6A)'        | 'CHIP'         | ''          | ''   | '20191128'  
 'HCB2012KF-220T60/6A'          | 'SMLF'     | 'EMPTY'  | 'CX000220011'(!)           = ''              | ''                 | 'CX000220011'              |'L0805'| 'NA'                           | 'IO'       | 'EMI FILTER CHIP HCB2012KF220T60(22 6A)'        | 'CHIP'         | ''          | ''   | '20191128'  
 '0.33UH/65A'                   | 'SMLF'     | 'IND'    | 'CV+33^0MZ03'(!)           = ''              | ''                 | 'CV+33^0MZ03'              |'L_MMD12FD'| '0.33UH/65A'                   | 'DISCRETE' | 'IND SMD 0.33UH 20% 65A(MMD-12FD-R33M-V1Q'      | 'CHIP'         | ''          | ''   | '20191204'  
 '0.33UH/65A'                   | 'SMLF'     | 'EMPTY'  | 'CV+33^0MZ03'(!)           = ''              | ''                 | 'CV+33^0MZ03'              |'L_MMD12FD'| 'NA'                           | 'IO'       | 'IND SMD 0.33UH 20% 65A(MMD-12FD-R33M-V1Q'      | 'CHIP'         | ''          | ''   | '20191204'  
 '0.36UH/25A'                   | 'SMLF'     | 'IND'    | 'CV+36Q0MZ00'(!)           = ''              | ''                 | 'CV+36Q0MZ00'              |'L_ETQP4LR22AFM'| '0.36UH/25A'                   | 'DISCRETE' | 'IND SMD 0.36U +-20%,25A (ETQP4LR36AFM)'        | 'CHIP'         | ''          | ''   | '20191205'  
 '0.36UH/25A'                   | 'SMLF'     | 'EMPTY'  | 'CV+36Q0MZ00'(!)           = ''              | ''                 | 'CV+36Q0MZ00'              |'L_ETQP4LR22AFM'| 'NA'                           | 'IO'       | 'IND SMD 0.36U +-20%,25A (ETQP4LR36AFM)'        | 'CHIP'         | ''          | ''   | '20191205'  
 '0.24UH/24A'                   | 'SMLF'     | 'IND'    | 'CV+24P0MZ00'(!)           = ''              | ''                 | 'CV+24P0MZ00'              |'L_ETQP4LR22AFM'| '0.24UH/24A'                   | 'DISCRETE' | 'IND SMD 0.24UH +-20% 24A(ETQP4LR24AFM)'        | 'CHIP'         | ''          | ''   | '20191209'  
 '0.24UH/24A'                   | 'SMLF'     | 'EMPTY'  | 'CV+24P0MZ00'(!)           = ''              | ''                 | 'CV+24P0MZ00'              |'L_ETQP4LR22AFM'| 'NA'                           | 'IO'       | 'IND SMD 0.24UH +-20% 24A(ETQP4LR24AFM)'        | 'CHIP'         | ''          | ''   | '20191209'  
 '0.42UH/20A'                   | 'SMLF'     | 'IND'    | 'CV+42K0MZ02'(!)           = ''              | ''                 | 'CV+42K0MZ02'              |'L_ETQP4LR22AFM'| '0.42UH/20A'                   | 'DISCRETE' | 'IND SMD 0.42U +-20%,20A (ETQP4LR42AFM)'        | 'CHIP'         | ''          | ''   | '20191209'  
 '0.42UH/20A'                   | 'SMLF'     | 'EMPTY'  | 'CV+42K0MZ02'(!)           = ''              | ''                 | 'CV+42K0MZ02'              |'L_ETQP4LR22AFM'| 'NA'                           | 'IO'       | 'IND SMD 0.42U +-20%,20A (ETQP4LR42AFM)'        | 'CHIP'         | ''          | ''   | '20191209'  
 '1UH/24A'                      | 'SMLF'     | 'IND'    | 'CV-10P0MZ04'(!)           = 'Non-Preferred' | 'End of Life'      | 'CV-10P0MZ04'              |'L_EM-10AM34VG1_7-9X7-1_EOL'| '1UH/24A'                      | 'DISCRETE' | 'IND SMD 1UH 20% 24A(EM-10AM34VG1)'             | 'CHIP'         | ''          | ''   | '20191209'  
 '1UH/24A'                      | 'SMLF'     | 'EMPTY'  | 'CV-10P0MZ04'(!)           = 'Non-Preferred' | 'End of Life'      | 'CV-10P0MZ04'              |'L_EM-10AM34VG1_7-9X7-1_EOL'| 'NA'                           | 'IO'       | 'IND SMD 1UH 20% 24A(EM-10AM34VG1)'             | 'CHIP'         | ''          | ''   | '20191209'  
 'MMZ1608D500CT/500MA'          | 'SMLF'     | 'IND'    | 'CX08D500000'(!)           = ''              | 'End of Life'      | 'CX08D500000'              |'L0603_EOL'| 'MMZ1608D500CT/500MA'          | 'DISCRETE' | 'EMI FILTER CHIP MMZ1608D500CT(50,500MA)'       | 'CHIP'         | ''          | ''   | '20191210'  
 'MMZ1608D500CT/500MA'          | 'SMLF'     | 'EMPTY'  | 'CX08D500000'(!)           = ''              | 'End of Life'      | 'CX08D500000'              |'L0603_EOL'| 'NA'                           | 'IO'       | 'EMI FILTER CHIP MMZ1608D500CT(50,500MA)'       | 'CHIP'         | ''          | ''   | '20191210'  
 '5.6NH/0.75A'                  | 'SMLF'     | 'IND'    | 'CVB5608TN02'(!)           = ''              | ''                 | 'CVB5608TN02'              |'L0603_H40'| '5.6NH/0.75A'                  | 'DISCRETE' | 'IND CHIP 5.6N+-0.2N 0.75A(LQW18AN5N6C00D'      | 'CHIP'         | ''          | ''   | '20191210'  
 '5.6NH/0.75A'                  | 'SMLF'     | 'EMPTY'  | 'CVB5608TN02'(!)           = ''              | ''                 | 'CVB5608TN02'              |'L0603_H40'| 'NA'                           | 'IO'       | 'IND CHIP 5.6N+-0.2N 0.75A(LQW18AN5N6C00D'      | 'CHIP'         | ''          | ''   | '20191210'  
 '0.42UH/22A'                   | 'SMLF'     | 'IND'    | 'CV+42M0MZ03'(!)           = ''              | ''                 | 'CV+42M0MZ03'              |'L_VCMT063T-2R2MN5_H158'| '0.42UH/22A'                   | 'DISCRETE' | 'IND SMD 0.42UH +-20% 22A(PCME064T-R42M)'       | 'CHIP'         | ''          | ''   | '20191231'  
 '0.42UH/22A'                   | 'SMLF'     | 'EMPTY'  | 'CV+42M0MZ03'(!)           = ''              | ''                 | 'CV+42M0MZ03'              |'L_VCMT063T-2R2MN5_H158'| 'NA'                           | 'IO'       | 'IND SMD 0.42UH +-20% 22A(PCME064T-R42M)'       | 'CHIP'         | ''          | ''   | '20191231'  
 '0.68UH/10.2A'                 | 'SMLF'     | 'IND'    | 'CV+68A2MZ00'(!)           = ''              | ''                 | 'CV+68A2MZ00'              |'L_MMD-05CZ-3R3M-M2Q'| '0.68UH/10.2A'                 | 'DISCRETE' | 'IND SMD 0.68UH20%10.2A MMD-05CZ-R68M-V1Q'      | 'CHIP'         | ''          | ''   | '20191231'  
 '0.68UH/10.2A'                 | 'SMLF'     | 'EMPTY'  | 'CV+68A2MZ00'(!)           = ''              | ''                 | 'CV+68A2MZ00'              |'L_MMD-05CZ-3R3M-M2Q'| 'NA'                           | 'IO'       | 'IND SMD 0.68UH20%10.2A MMD-05CZ-R68M-V1Q'      | 'CHIP'         | ''          | ''   | '20191231'  
 '2.2UH/5.8A'                   | 'SMLF'     | 'IND'    | 'CV-2258MZ05'(!)           = ''              | ''                 | 'CV-2258MZ05'              |'L_MMD-05CZ-3R3M-M2Q'| '2.2UH/5.8A'                   | 'DISCRETE' | 'IND SMD 2.2UH 20% 5.8A(MMD-05CZ-2R2M-V1Q'      | 'CHIP'         | ''          | ''   | '20200102'  
 '2.2UH/5.8A'                   | 'SMLF'     | 'EMPTY'  | 'CV-2258MZ05'(!)           = ''              | ''                 | 'CV-2258MZ05'              |'L_MMD-05CZ-3R3M-M2Q'| 'NA'                           | 'IO'       | 'IND SMD 2.2UH 20% 5.8A(MMD-05CZ-2R2M-V1Q'      | 'CHIP'         | ''          | ''   | '20200102'  
 'BLM31SN500SN1L/10A'           | 'SMLF'     | 'IND'    | 'CX1SN500001'(!)           = ''              | ''                 | 'CX1SN500001'              |'L1206XG'| 'BLM31SN500SN1L/10A'           | 'DISCRETE' | 'EMI FILTER BEAD BLM31SN500SN1L(50,10A)'        | 'CHIP'         | ''          | ''   | '20200109'  
 'BLM31SN500SN1L/10A'           | 'SMLF'     | 'EMPTY'  | 'CX1SN500001'(!)           = ''              | ''                 | 'CX1SN500001'              |'L1206XG'| 'NA'                           | 'IO'       | 'EMI FILTER BEAD BLM31SN500SN1L(50,10A)'        | 'CHIP'         | ''          | ''   | '20200109'  
 '120NH/103A'                   | 'SMLF'     | 'IND'    | 'CV+12^0TZ03'(!)           = ''              | ''                 | 'CV+12^0TZ03'              |'L_HCME1012Q-121QL_10X6'| '120NH/103A'                   | 'DISCRETE' | 'IND SMD 120NH 15% 103A(HCME1012Q)1MHZ'         | 'CHIP'         | ''          | ''   | '20200117'  
 '120NH/103A'                   | 'SMLF'     | 'EMPTY'  | 'CV+12^0TZ03'(!)           = ''              | ''                 | 'CV+12^0TZ03'              |'L_HCME1012Q-121QL_10X6'| 'NA'                           | 'IO'       | 'IND SMD 120NH 15% 103A(HCME1012Q)1MHZ'         | 'CHIP'         | ''          | ''   | '20200117'  
 '50NH/148A'                    | 'SMLF'     | 'IND'    | 'CVA50^0TZ00'(!)           = ''              | ''                 | 'CVA50^0TZ00'              |'L_HCBS1080-500QL_10X8-3'| '50NH/148A'                    | 'DISCRETE' | 'IND SMD 50NH 15% 148A(HCBS1080-500QL)'         | 'CHIP'         | ''          | ''   | '20200207'  
 '50NH/148A'                    | 'SMLF'     | 'EMPTY'  | 'CVA50^0TZ00'(!)           = ''              | ''                 | 'CVA50^0TZ00'              |'L_HCBS1080-500QL_10X8-3'| 'NA'                           | 'IO'       | 'IND SMD 50NH 15% 148A(HCBS1080-500QL)'         | 'CHIP'         | ''          | ''   | '20200207'  
 '120NH/107A'                   | 'SMLF'     | 'IND'    | 'CV+12^0TZ04'(!)           = ''              | ''                 | 'CV+12^0TZ04'              |'L_L101247A-120L_10X6-4'| '120NH/107A'                   | 'DISCRETE' | 'IND SMD 120NH 15% 107A(L101247A-120L)'         | 'CHIP'         | ''          | ''   | '20200210'  
 '120NH/107A'                   | 'SMLF'     | 'EMPTY'  | 'CV+12^0TZ04'(!)           = ''              | ''                 | 'CV+12^0TZ04'              |'L_L101247A-120L_10X6-4'| 'NA'                           | 'IO'       | 'IND SMD 120NH 15% 107A(L101247A-120L)'         | 'CHIP'         | ''          | ''   | '20200210'  
 '120NH/94A'                    | 'SMLF'     | 'IND'    | 'CV+12^0KZ14'(!)           = ''              | ''                 | 'CV+12^0KZ14'              |'L_AF13A-120K_9-6X6-4'| '120NH/94A'                    | 'DISCRETE' | 'IND SMD 120NH 10% 94A(AF13A-120K)'             | 'CHIP'         | ''          | ''   | '20200210'  
 '120NH/94A'                    | 'SMLF'     | 'EMPTY'  | 'CV+12^0KZ14'(!)           = ''              | ''                 | 'CV+12^0KZ14'              |'L_AF13A-120K_9-6X6-4'| 'NA'                           | 'IO'       | 'IND SMD 120NH 10% 94A(AF13A-120K)'             | 'CHIP'         | ''          | ''   | '20200210'  
 '0.12UH/105A'                  | 'SMLF'     | 'IND'    | 'CV+12^0TZ00'(!)           = 'End of Design' | 'Comp-Approve'     | 'CV+12^0TZ00'              |'L_HCME1012Q-121QL_10X6'| '0.12UH/105A'                  | 'DISCRETE' | 'IND SMD 0.12UH +-15% 105A(PA4990.121HLT)'      | 'CHIP'         | ''          | ''   | '20200219'  
 '0.12UH/105A'                  | 'SMLF'     | 'EMPTY'  | 'CV+12^0TZ00'(!)           = 'End of Design' | 'Comp-Approve'     | 'CV+12^0TZ00'              |'L_HCME1012Q-121QL_10X6'| 'NA'                           | 'IO'       | 'IND SMD 0.12UH +-15% 105A(PA4990.121HLT)'      | 'CHIP'         | ''          | ''   | '20200219'  
 '0.33UH/40A'                   | 'SMLF'     | 'IND'    | 'CV+33^0TZ00'(!)           = 'End of Design' | 'Comp-Approve'     | 'CV+33^0TZ00'              |'L_HCME1012Q-121QL_10X6'| '0.33UH/40A'                   | 'DISCRETE' | 'IND SMD 0.33UH +-15% 40A(PA4990.331HLT)'       | 'CHIP'         | ''          | ''   | '20200219'  
 '0.33UH/40A'                   | 'SMLF'     | 'EMPTY'  | 'CV+33^0TZ00'(!)           = 'End of Design' | 'Comp-Approve'     | 'CV+33^0TZ00'              |'L_HCME1012Q-121QL_10X6'| 'NA'                           | 'IO'       | 'IND SMD 0.33UH +-15% 40A(PA4990.331HLT)'       | 'CHIP'         | ''          | ''   | '20200219'  
 '1.0UH/8.5A'                   | 'SMLF'     | 'IND'    | 'CV-1085MZ05'(!)           = ''              | ''                 | 'CV-1085MZ05'              |'L_HCM0503_5-15X5-1'| '1.0UH/8.5A'                   | 'DISCRETE' | 'IND SMD 1.0UH +-20% 8.5A(HCM0503-1R0-R)'       | 'CHIP'         | ''          | ''   | '20200219'  
 '1.0UH/8.5A'                   | 'SMLF'     | 'EMPTY'  | 'CV-1085MZ05'(!)           = ''              | ''                 | 'CV-1085MZ05'              |'L_HCM0503_5-15X5-1'| 'NA'                           | 'IO'       | 'IND SMD 1.0UH +-20% 8.5A(HCM0503-1R0-R)'       | 'CHIP'         | ''          | ''   | '20200219'  
 '150NH/60A'                    | 'SMLF'     | 'IND'    | 'CV+15^0KZ20'(!)           = ''              | ''                 | 'CV+15^0KZ20'              |'L_AH3740A-100K_9-5X6-4'| '150NH/60A'                    | 'DISCRETE' | 'IND SMD 150NH 10% 60A(AH3740A-150K)'           | 'CHIP'         | ''          | ''   | '20200219'  
 '150NH/60A'                    | 'SMLF'     | 'EMPTY'  | 'CV+15^0KZ20'(!)           = ''              | ''                 | 'CV+15^0KZ20'              |'L_AH3740A-100K_9-5X6-4'| 'NA'                           | 'IO'       | 'IND SMD 150NH 10% 60A(AH3740A-150K)'           | 'CHIP'         | ''          | ''   | '20200219'  
 '55NH/30A'                     | 'SMLF'     | 'IND'    | 'CVA55V0MZ00'(!)           = ''              | ''                 | 'CVA55V0MZ00'              |'L_HCB65-550X_5-5X5-7'| '55NH/30A'                     | 'DISCRETE' | 'IND SMD 55NH +-20% 30A(HCB65-550X)'            | 'CHIP'         | ''          | ''   | '20200219'  
 '55NH/30A'                     | 'SMLF'     | 'EMPTY'  | 'CVA55V0MZ00'(!)           = ''              | ''                 | 'CVA55V0MZ00'              |'L_HCB65-550X_5-5X5-7'| 'NA'                           | 'IO'       | 'IND SMD 55NH +-20% 30A(HCB65-550X)'            | 'CHIP'         | ''          | ''   | '20200219'  
 '90NH/155AA'                   | 'SMLF'     | 'IND'    | 'CVA90^0KZ04'(!)           = ''              | ''                 | 'CVA90^0KZ04'              |'L_HCME107512Q-900QL_10X7-7'| '90NH/155A'                    | 'DISCRETE' | 'IND SMD 90NH 10% 155A(HCME107512Q)1MHZ'        | 'CHIP'         | ''          | ''   | '20200221'  
 '90NH/155AA'                   | 'SMLF'     | 'EMPTY'  | 'CVA90^0KZ04'(!)           = ''              | ''                 | 'CVA90^0KZ04'              |'L_HCME107512Q-900QL_10X7-7'| 'NA'                           | 'IO'       | 'IND SMD 90NH 10% 155A(HCME107512Q)1MHZ'        | 'CHIP'         | ''          | ''   | '20200221'  
 '90NH/137A'                    | 'SMLF'     | 'IND'    | 'CVA90^0KZ05'(!)           = ''              | ''                 | 'CVA90^0KZ05'              |'L_HCUVE768012Q-900QL_7-6X8-3'| '90NH/137A'                    | 'DISCRETE' | 'IND SMD 90NH 10% 137A(HCUVE768012Q)1MHZ'       | 'CHIP'         | ''          | ''   | '20200221'  
 '90NH/137A'                    | 'SMLF'     | 'EMPTY'  | 'CVA90^0KZ05'(!)           = ''              | ''                 | 'CVA90^0KZ05'              |'L_HCUVE768012Q-900QL_7-6X8-3'| 'NA'                           | 'IO'       | 'IND SMD 90NH 10% 137A(HCUVE768012Q)1MHZ'       | 'CHIP'         | ''          | ''   | '20200221'  
 'MPZ2012S300ATD25/6A'          | 'SMLF'     | 'IND'    | 'CX12S300000'(!)           = ''              | ''                 | 'CX12S300000'              |'L0805'| 'MPZ2012S300ATD25/6A'          | 'DISCRETE' | 'EMI FIL MPZ2012S300ATD25(30,6A)'               | 'CHIP'         | ''          | ''   | '20200221'  
 'MPZ2012S300ATD25/6A'          | 'SMLF'     | 'EMPTY'  | 'CX12S300000'(!)           = ''              | ''                 | 'CX12S300000'              |'L0805'| 'NA'                           | 'IO'       | 'EMI FIL MPZ2012S300ATD25(30,6A)'               | 'CHIP'         | ''          | ''   | '20200221'  
 '1UH/20.5A'                    | 'SMLF'     | 'IND'    | 'CV-10K5TZ00'(!)           = 'End of Design' | 'Comp-Approve'     | 'CV-10K5TZ00'              |'L_PA4987_10X7'| '1UH/20.5A'                    | 'DISCRETE' | 'IND SMD 1UH +-15% 20.5A(PA4987.102HLT'         | 'CHIP'         | ''          | ''   | '20200221'  
 '1UH/20.5A'                    | 'SMLF'     | 'EMPTY'  | 'CV-10K5TZ00'(!)           = 'End of Design' | 'Comp-Approve'     | 'CV-10K5TZ00'              |'L_PA4987_10X7'| 'NA'                           | 'IO'       | 'IND SMD 1UH +-15% 20.5A(PA4987.102HLT'         | 'CHIP'         | ''          | ''   | '20200221'  
 '1.0UH/2.66A'                  | 'SMLF'     | 'IND'    | 'CV-1027MZ14'(!)           = ''              | ''                 | 'CV-1027MZ14'              |'L_LD1-1R0-R_4-5X4'| '1.0UH/2.66A'                  | 'DISCRETE' | 'IND SMD 1.0UH +-20% 2.66A(LD1-1R0-R)'          | 'CHIP'         | ''          | ''   | '20200306'  
 '1.0UH/2.66A'                  | 'SMLF'     | 'EMPTY'  | 'CV-1027MZ14'(!)           = ''              | ''                 | 'CV-1027MZ14'              |'L_LD1-1R0-R_4-5X4'| 'NA'                           | 'IO'       | 'IND SMD 1.0UH +-20% 2.66A(LD1-1R0-R)'          | 'CHIP'         | ''          | ''   | '20200306'  
 'BLM15BB121SN1D/300'           | 'SMLF'     | 'IND'    | 'CX5BB121007'(!)           = ''              | ''                 | 'CX5BB121007'              |'L0402'| 'BLM15BB121SN1D/300'           | 'DISCRETE' | 'EMI FILTER BLM15BB121SN1D(120,300)'            | 'CHIP'         | ''          | ''   | '20200316'  
 'BLM15BB121SN1D/300'           | 'SMLF'     | 'EMPTY'  | 'CX5BB121007'(!)           = ''              | ''                 | 'CX5BB121007'              |'L0402'| 'NA'                           | 'IO'       | 'EMI FILTER BLM15BB121SN1D(120,300)'            | 'CHIP'         | ''          | ''   | '20200316'  
 '3.7UH/45A'                    | 'SMLF'     | 'IND'    | 'CV-37^0TZ01'(!)           = ''              | ''                 | 'CV-37^0TZ01'              |'LC_61126_H504'| '3.7UH/45A'                    | 'DISCRETE' | 'IND SMD 3.7UH +15/-30% 45A(61126R04)'          | 'CHIP'         | ''          | ''   | '20200317'  
 '3.7UH/45A'                    | 'SMLF'     | 'EMPTY'  | 'CV-37^0TZ01'(!)           = ''              | ''                 | 'CV-37^0TZ01'              |'LC_61126_H504'| 'NA'                           | 'IO'       | 'IND SMD 3.7UH +15/-30% 45A(61126R04)'          | 'CHIP'         | ''          | ''   | '20200317'  
 'BLM18RK121SN1D/200MA'         | 'SMLF'     | 'IND'    | 'CW8RK121001'(!)           = ''              | ''                 | 'CW8RK121001'              |'L0603'| 'BLM18RK121SN1D/200MA'         | 'DISCRETE' | 'FERRITE BEAD BLM18RK121SN1D(100M)'             | 'CHIP'         | ''          | ''   | '20200320'  
 'BLM18RK121SN1D/200MA'         | 'SMLF'     | 'EMPTY'  | 'CW8RK121001'(!)           = ''              | ''                 | 'CW8RK121001'              |'L0603'| 'NA'                           | 'IO'       | 'FERRITE BEAD BLM18RK121SN1D(100M)'             | 'CHIP'         | ''          | ''   | '20200320'  
 'BLM31PG330SN1L/6A'            | 'SMLF'     | 'IND'    | 'CX1PG330004'(!)           = ''              | ''                 | 'CX1PG330004'              |'L1206XF'| 'BLM31PG330SN1L/6A'            | 'DISCRETE' | 'EMI FILTER CHIP BLM31PG330SN1(33,6A)'          | 'CHIP'         | ''          | ''   | '20200325'  
 'BLM31PG330SN1L/6A'            | 'SMLF'     | 'EMPTY'  | 'CX1PG330004'(!)           = ''              | ''                 | 'CX1PG330004'              |'L1206XF'| 'NA'                           | 'IO'       | 'EMI FILTER CHIP BLM31PG330SN1(33,6A)'          | 'CHIP'         | ''          | ''   | '20200325'  
 '0.47UH/23A'                   | 'SMLF'     | 'IND'    | 'CV+47N0MZ00'(!)           = 'End of Design' | 'Comp-Approve'     | 'CV+47N0MZ00'              |'L_VRMXA'| '0.47UH/23A'                   | 'DISCRETE' | 'IND SMD 0.47UH +-20% 23A(PA0515.471NLT)'       | 'CHIP'         | ''          | ''   | '20200401'  
 '0.47UH/23A'                   | 'SMLF'     | 'EMPTY'  | 'CV+47N0MZ00'(!)           = 'End of Design' | 'Comp-Approve'     | 'CV+47N0MZ00'              |'L_VRMXA'| 'NA'                           | 'IO'       | 'IND SMD 0.47UH +-20% 23A(PA0515.471NLT)'       | 'CHIP'         | ''          | ''   | '20200401'  
 '0.47UH/30A'                   | 'SMLF'     | 'IND'    | 'CV+47V0TZ00'(!)           = ''              | ''                 | 'CV+47V0TZ00'              |'L_MSI-111109-R47L-IS_11-2X11-2'| '0.47UH/30A'                   | 'DISCRETE' | 'IND SMD 0.47UH 15% 30A(MSI-111109-R47L)'       | 'CHIP'         | ''          | ''   | '20200331'  
 '0.47UH/30A'                   | 'SMLF'     | 'EMPTY'  | 'CV+47V0TZ00'(!)           = ''              | ''                 | 'CV+47V0TZ00'              |'L_MSI-111109-R47L-IS_11-2X11-2'| 'NA'                           | 'IO'       | 'IND SMD 0.47UH 15% 30A(MSI-111109-R47L)'       | 'CHIP'         | ''          | ''   | '20200331'  
 '0.12UH/69A'                   | 'SMLF'     | 'IND'    | 'CV+12^0TZ05'(!)           = ''              | ''                 | 'CV+12^0TZ05'              |'L_VLBU6565100T-R12L_6-5X6-5'| '0.12UH/69A'                   | 'DISCRETE' | 'IND SMD 0.12UH 15% 69A(VLBU6565100T-R12L'      | 'CHIP'         | ''          | ''   | '20200421'  
 '0.12UH/69A'                   | 'SMLF'     | 'EMPTY'  | 'CV+12^0TZ05'(!)           = ''              | ''                 | 'CV+12^0TZ05'              |'L_VLBU6565100T-R12L_6-5X6-5'| 'NA'                           | 'IO'       | 'IND SMD 0.12UH 15% 69A(VLBU6565100T-R12L'      | 'CHIP'         | ''          | ''   | '20200421'  
 '90NH/155A'                    | 'SMLF'     | 'IND'    | 'CVA90^0KZ08'(!)           = ''              | ''                 | 'CVA90^0KZ08'              |'L_HCME107512Q-900QL_10X7-7'| '90NH/155A'                    | 'DISCRETE' | 'IND SMD 90NH 10% 155A(MSI-100812V-90NK)'       | 'CHIP'         | ''          | ''   | '20200420'  
 '90NH/155A'                    | 'SMLF'     | 'EMPTY'  | 'CVA90^0KZ08'(!)           = ''              | ''                 | 'CVA90^0KZ08'              |'L_HCME107512Q-900QL_10X7-7'| 'NA'                           | 'IO'       | 'IND SMD 90NH 10% 155A(MSI-100812V-90NK)'       | 'CHIP'         | ''          | ''   | '20200420'  
 '90NH/137A'                    | 'SMLF'     | 'IND'    | 'CVA90^0KZ09'(!)           = ''              | ''                 | 'CVA90^0KZ09'              |'L_HCUVE768012Q-900QL_7-6X8-3'| '90NH/137A'                    | 'DISCRETE' | 'IND SMD 90NH 10% 137A(MSI-800812V-90NK)'       | 'CHIP'         | ''          | ''   | '20200420'  
 '90NH/137A'                    | 'SMLF'     | 'EMPTY'  | 'CVA90^0KZ09'(!)           = ''              | ''                 | 'CVA90^0KZ09'              |'L_HCUVE768012Q-900QL_7-6X8-3'| 'NA'                           | 'IO'       | 'IND SMD 90NH 10% 137A(MSI-800812V-90NK)'       | 'CHIP'         | ''          | ''   | '20200420'  
 '90NH/138A'                    | 'SMLF'     | 'IND'    | 'CVA90^0TZ00'(!)           = ''              | ''                 | 'CVA90^0TZ00'              |'L_VLBU12060120R09LF3_12X6'| '90NH/138A'                    | 'DISCRETE' | 'IND SMD 90NH+-15%138A(VLBU12060120R09LF3'      | 'CHIP'         | ''          | ''   | '20200506'  
 '90NH/138A'                    | 'SMLF'     | 'EMPTY'  | 'CVA90^0TZ00'(!)           = ''              | ''                 | 'CVA90^0TZ00'              |'L_VLBU12060120R09LF3_12X6'| 'NA'                           | 'IO'       | 'IND SMD 90NH+-15%138A(VLBU12060120R09LF3'      | 'CHIP'         | ''          | ''   | '20200506'  
 '120NH/76A'                    | 'SMLF'     | 'IND'    | 'CV+12^0TZ06'(!)           = ''              | ''                 | 'CV+12^0TZ06'              |'L_HCME0711Q-121LQL_7X6-7'| '120NH/76A'                    | 'DISCRETE' | 'IND SMD 120NH 15% 76A(HCME0711Q-121LQL)'       | 'CHIP'         | ''          | ''   | '20200514'  
 '120NH/76A'                    | 'SMLF'     | 'EMPTY'  | 'CV+12^0TZ06'(!)           = ''              | ''                 | 'CV+12^0TZ06'              |'L_HCME0711Q-121LQL_7X6-7'| 'NA'                           | 'IO'       | 'IND SMD 120NH 15% 76A(HCME0711Q-121LQL)'       | 'CHIP'         | ''          | ''   | '20200514'  
 '1.5UH/1.7A'                   | 'SMLF'     | 'IND'    | 'CV-1517MZ00'(!)           = ''              | ''                 | 'CV-1517MZ00'              |'L_BDHE002012101R5MQ1_2X1-25'| '1.5UH/1.7A'                   | 'DISCRETE' | 'IND SMD 1.5UH20% 1.7A(BDHE002012101R5MQ1'      | 'CHIP'         | ''          | ''   | '20200526'  
 '1.5UH/1.7A'                   | 'SMLF'     | 'EMPTY'  | 'CV-1517MZ00'(!)           = ''              | ''                 | 'CV-1517MZ00'              |'L_BDHE002012101R5MQ1_2X1-25'| 'NA'                           | 'IO'       | 'IND SMD 1.5UH20% 1.7A(BDHE002012101R5MQ1'      | 'CHIP'         | ''          | ''   | '20200526'  
 '1.5UH/1.6A'                   | 'SMLF'     | 'IND'    | 'CV-1516MN00'(!)           = ''              | ''                 | 'CV-1516MN00'              |'L0805'| '1.5UH/1.6A'                   | 'DISCRETE' | 'IND CHIP 1.5UH 20% 1.6A(DFE201210U-1R5M)'      | 'CHIP'         | ''          | ''   | '20200526'  
 '1.5UH/1.6A'                   | 'SMLF'     | 'EMPTY'  | 'CV-1516MN00'(!)           = ''              | ''                 | 'CV-1516MN00'              |'L0805'| 'NA'                           | 'IO'       | 'IND CHIP 1.5UH 20% 1.6A(DFE201210U-1R5M)'      | 'CHIP'         | ''          | ''   | '20200526'  
 '130NH/106A'                   | 'SMLF'     | 'IND'    | 'CV+13^0KZ11'(!)           = 'End of Design' | 'Comp-Approve'     | 'CV+13^0KZ11'              |'L_HCME107512-131_10X7-5'| '130NH/106A'                   | 'DISCRETE' | 'IND SMD 130NH 10% 106A(PG2323.131HLT)'         | 'CHIP'         | ''          | ''   | '20200608'  
 '130NH/106A'                   | 'SMLF'     | 'EMPTY'  | 'CV+13^0KZ11'(!)           = 'End of Design' | 'Comp-Approve'     | 'CV+13^0KZ11'              |'L_HCME107512-131_10X7-5'| 'NA'                           | 'IO'       | 'IND SMD 130NH 10% 106A(PG2323.131HLT)'         | 'CHIP'         | ''          | ''   | '20200608'  
 '130NH/95A'                    | 'SMLF'     | 'IND'    | 'CV+13^0KZ10'(!)           = 'End of Design' | 'Comp-Approve'     | 'CV+13^0KZ10'              |'L_HCUVE768012-171_7-6X8-1'| '130NH/95A'                    | 'DISCRETE' | 'IND SMD 130NH 10% 95A(PGL6076.131HLT)'         | 'CHIP'         | ''          | ''   | '20200608'  
 '130NH/95A'                    | 'SMLF'     | 'EMPTY'  | 'CV+13^0KZ10'(!)           = 'End of Design' | 'Comp-Approve'     | 'CV+13^0KZ10'              |'L_HCUVE768012-171_7-6X8-1'| 'NA'                           | 'IO'       | 'IND SMD 130NH 10% 95A(PGL6076.131HLT)'         | 'CHIP'         | ''          | ''   | '20200608'  
 '90NH/137A'                    | 'SMLF'     | 'IND'    | 'CVA90^0KZ10'(!)           = 'End of Design' | 'Comp-Approve'     | 'CVA90^0KZ10'              |'L_HCUVE768012Q-900QL_7-6X8-3'| '90NH/137A'                    | 'DISCRETE' | 'IND SMD 90NH 10% 137A(PGL6076.900HLT)'         | 'CHIP'         | ''          | ''   | '20200608'  
 '90NH/137A'                    | 'SMLF'     | 'EMPTY'  | 'CVA90^0KZ10'(!)           = 'End of Design' | 'Comp-Approve'     | 'CVA90^0KZ10'              |'L_HCUVE768012Q-900QL_7-6X8-3'| 'NA'                           | 'IO'       | 'IND SMD 90NH 10% 137A(PGL6076.900HLT)'         | 'CHIP'         | ''          | ''   | '20200608'  
 '90NH/140A'                    | 'SMLF'     | 'IND'    | 'CVA90^0EZ00'(!)           = ''              | ''                 | 'CVA90^0EZ00'              |'L_HCME1211GQ-900QL_12X6'| '90NH/140A'                    | 'DISCRETE' | 'IND SMD 90NH 15% 140A(HCME1211GQ-900QL)'       | 'CHIP'         | ''          | ''   | '20200611'  
 '90NH/140A'                    | 'SMLF'     | 'EMPTY'  | 'CVA90^0EZ00'(!)           = ''              | ''                 | 'CVA90^0EZ00'              |'L_HCME1211GQ-900QL_12X6'| 'NA'                           | 'IO'       | 'IND SMD 90NH 15% 140A(HCME1211GQ-900QL)'       | 'CHIP'         | ''          | ''   | '20200611'  
 '50NH/148A'                    | 'SMLF'     | 'IND'    | 'CVA50^0EZ01'(!)           = 'End of Design' | 'Comp-Approve'     | 'CVA50^0EZ01'              |'L_HCBS1080-500QL_10X8-3'| '50NH/148A'                    | 'DISCRETE' | 'IND SMD 50NH 15% 148A(PGL6189.500HLT)'         | 'CHIP'         | ''          | ''   | '20200620'  
 '50NH/148A'                    | 'SMLF'     | 'EMPTY'  | 'CVA50^0EZ01'(!)           = 'End of Design' | 'Comp-Approve'     | 'CVA50^0EZ01'              |'L_HCBS1080-500QL_10X8-3'| 'NA'                           | 'IO'       | 'IND SMD 50NH 15% 148A(PGL6189.500HLT)'         | 'CHIP'         | ''          | ''   | '20200620'  
 '150NH/75A'                    | 'SMLF'     | 'IND'    | 'CV+15^0KZ24'(!)           = ''              | ''                 | 'CV+15^0KZ24'              |'L_AF13A-120K_9-6X6-4'| '150NH/75A'                    | 'DISCRETE' | 'IND SMD 150NH 10% 75A(PG1712.151AHLT)'         | 'CHIP'         | ''          | ''   | '20200703'  
 '150NH/75A'                    | 'SMLF'     | 'EMPTY'  | 'CV+15^0KZ24'(!)           = ''              | ''                 | 'CV+15^0KZ24'              |'L_AF13A-120K_9-6X6-4'| 'NA'                           | 'IO'       | 'IND SMD 150NH 10% 75A(PG1712.151AHLT)'         | 'CHIP'         | ''          | ''   | '20200703'  
 '120NH/94A'                    | 'SMLF'     | 'IND'    | 'CV+12^0KZ16'(!)           = ''              | ''                 | 'CV+12^0KZ16'              |'L_AF13A-120K_9-6X6-4'| '120NH/94A'                    | 'DISCRETE' | 'IND SMD 120NH 10% 94A(PG1712.121AHLT)'         | 'CHIP'         | ''          | ''   | '20200703'  
 '120NH/94A'                    | 'SMLF'     | 'EMPTY'  | 'CV+12^0KZ16'(!)           = ''              | ''                 | 'CV+12^0KZ16'              |'L_AF13A-120K_9-6X6-4'| 'NA'                           | 'IO'       | 'IND SMD 120NH 10% 94A(PG1712.121AHLT)'         | 'CHIP'         | ''          | ''   | '20200703'  
 '90NH/134A'                    | 'SMLF'     | 'IND'    | 'CVA90^0KZ11'(!)           = ''              | ''                 | 'CVA90^0KZ11'              |'L_AF13A-120K_9-6X6-4'| '90NH/134A'                    | 'DISCRETE' | 'IND SMD 90NH 10% 134A(PG1712.900AHLT)'         | 'CHIP'         | ''          | ''   | '20200703'  
 '90NH/134A'                    | 'SMLF'     | 'EMPTY'  | 'CVA90^0KZ11'(!)           = ''              | ''                 | 'CVA90^0KZ11'              |'L_AF13A-120K_9-6X6-4'| 'NA'                           | 'IO'       | 'IND SMD 90NH 10% 134A(PG1712.900AHLT)'         | 'CHIP'         | ''          | ''   | '20200703'  
 '300NH/33A'                    | 'SMLF'     | 'IND'    | 'CV+30Y0KZ05'(!)           = ''              | ''                 | 'CV+30Y0KZ05'              |'L_AF13A-120K_9-6X6-4'| '300NH/33A'                    | 'DISCRETE' | 'IND SMD 300NH 10% 33A(PG1712.301AHLT)'         | 'CHIP'         | ''          | ''   | '20200703'  
 '300NH/33A'                    | 'SMLF'     | 'EMPTY'  | 'CV+30Y0KZ05'(!)           = ''              | ''                 | 'CV+30Y0KZ05'              |'L_AF13A-120K_9-6X6-4'| 'NA'                           | 'IO'       | 'IND SMD 300NH 10% 33A(PG1712.301AHLT)'         | 'CHIP'         | ''          | ''   | '20200703'  
 '220NH/61A'                    | 'SMLF'     | 'IND'    | 'CV+22^0KZ37'(!)           = ''              | ''                 | 'CV+22^0KZ37'              |'L_HCUVE966412D-221'| '220NH/61A'                    | 'DISCRETE' | 'IND SMD 220NH 10% 61A(PGL6216.221HLT)'         | 'CHIP'         | ''          | ''   | '20200707'  
 '220NH/61A'                    | 'SMLF'     | 'EMPTY'  | 'CV+22^0KZ37'(!)           = ''              | ''                 | 'CV+22^0KZ37'              |'L_HCUVE966412D-221'| 'NA'                           | 'IO'       | 'IND SMD 220NH 10% 61A(PGL6216.221HLT)'         | 'CHIP'         | ''          | ''   | '20200707'  
 '50NH/148A'                    | 'SMLF'     | 'IND'    | 'CVA50^0EZ02'(!)           = ''              | ''                 | 'CVA50^0EZ02'              |'L_HCBS1080-500QL_10X8-3'| '50NH/148A'                    | 'DISCRETE' | 'IND SMD 50NH 15% 148A(EB-50CL3SP01)'           | 'CHIP'         | ''          | ''   | '20200714'  
 '50NH/148A'                    | 'SMLF'     | 'EMPTY'  | 'CVA50^0EZ02'(!)           = ''              | ''                 | 'CVA50^0EZ02'              |'L_HCBS1080-500QL_10X8-3'| 'NA'                           | 'IO'       | 'IND SMD 50NH 15% 148A(EB-50CL3SP01)'           | 'CHIP'         | ''          | ''   | '20200714'  
 '70NH/60A'                     | 'SMLF'     | 'IND'    | 'CVA70^0MZ07'(!)           = 'End of Design' | 'Comp-Approve'     | 'CVA70^0MZ07'              |'L_MSI-600607_6-1X6'| '70NH/60A'                     | 'DISCRETE' | 'IND SMD 70NH 20% 60A(PG2292.700HLT)'           | 'CHIP'         | ''          | ''   | '20200727'  
 '70NH/60A'                     | 'SMLF'     | 'EMPTY'  | 'CVA70^0MZ07'(!)           = 'End of Design' | 'Comp-Approve'     | 'CVA70^0MZ07'              |'L_MSI-600607_6-1X6'| 'NA'                           | 'IO'       | 'IND SMD 70NH 20% 60A(PG2292.700HLT)'           | 'CHIP'         | ''          | ''   | '20200727'  
 '50NH/86A'                     | 'SMLF'     | 'IND'    | 'CVA50^0MZ09'(!)           = 'End of Design' | 'Comp-Approve'     | 'CVA50^0MZ09'              |'L_MSI-600607_6-1X6'| '50NH/86A'                     | 'DISCRETE' | 'IND SMD 50NH 20% 86A(PG2292.500HLT)'           | 'CHIP'         | ''          | ''   | '20200727'  
 '50NH/86A'                     | 'SMLF'     | 'EMPTY'  | 'CVA50^0MZ09'(!)           = 'End of Design' | 'Comp-Approve'     | 'CVA50^0MZ09'              |'L_MSI-600607_6-1X6'| 'NA'                           | 'IO'       | 'IND SMD 50NH 20% 86A(PG2292.500HLT)'           | 'CHIP'         | ''          | ''   | '20200727'  
 '1.0UH/50A'                    | 'SMLF'     | 'IND'    | 'CV-10^0MZ03'(!)           = ''              | ''                 | 'CV-10^0MZ03'              |'L_MMD12EZXA'| '1.0UH/50A'                    | 'DISCRETE' | 'IND SMD 1.0UH 20% 50A(MMD-12EZ-1R0M-V1Q)'      | 'CHIP'         | ''          | ''   | '20200727'  
 '1.0UH/50A'                    | 'SMLF'     | 'EMPTY'  | 'CV-10^0MZ03'(!)           = ''              | ''                 | 'CV-10^0MZ03'              |'L_MMD12EZXA'| 'NA'                           | 'IO'       | 'IND SMD 1.0UH 20% 50A(MMD-12EZ-1R0M-V1Q)'      | 'CHIP'         | ''          | ''   | '20200727'  
 '100NH/16A'                    | 'SMLF'     | 'IND'    | 'CV+10G0MZ12'(!)           = 'End of Design' | 'Comp-Approve'     | 'CV+10G0MZ12'              |'L_PG2289101HLT_4-5X4-7'| '100NH/16A'                    | 'DISCRETE' | 'IND SMD 100NH 20% 16A(PG2289.101HLT)'          | 'CHIP'         | ''          | ''   | '20200728'  
 '100NH/16A'                    | 'SMLF'     | 'EMPTY'  | 'CV+10G0MZ12'(!)           = 'End of Design' | 'Comp-Approve'     | 'CV+10G0MZ12'              |'L_PG2289101HLT_4-5X4-7'| 'NA'                           | 'IO'       | 'IND SMD 100NH 20% 16A(PG2289.101HLT)'          | 'CHIP'         | ''          | ''   | '20200728'  
 '120NH/105A'                   | 'SMLF'     | 'IND'    | 'CV+12^0KZ13'(!)           = 'End of Design' | 'Comp-Approve'     | 'CV+12^0KZ13'              |'L_PGL6054121HLT_10X6'| '120NH/105A'                   | 'DISCRETE' | 'IND SMD 120NH +-10% 105A(PGL6054.121HLT)'      | 'CHIP'         | ''          | ''   | '20200727'  
 '120NH/105A'                   | 'SMLF'     | 'EMPTY'  | 'CV+12^0KZ13'(!)           = 'End of Design' | 'Comp-Approve'     | 'CV+12^0KZ13'              |'L_PGL6054121HLT_10X6'| 'NA'                           | 'IO'       | 'IND SMD 120NH +-10% 105A(PGL6054.121HLT)'      | 'CHIP'         | ''          | ''   | '20200727'  
 '320NH/37A'                    | 'SMLF'     | 'IND'    | 'CV+32^0KZ13'(!)           = ''              | ''                 | 'CV+32^0KZ13'              |'L_HCUVE768012-171_7-6X8-1'| '320NH/37A'                    | 'DISCRETE' | 'IND SMD 320NH 10% 37A(HCUVE768012Q-321QL'      | 'CHIP'         | ''          | ''   | '20200803'  
 '320NH/37A'                    | 'SMLF'     | 'EMPTY'  | 'CV+32^0KZ13'(!)           = ''              | ''                 | 'CV+32^0KZ13'              |'L_HCUVE768012-171_7-6X8-1'| 'NA'                           | 'IO'       | 'IND SMD 320NH 10% 37A(HCUVE768012Q-321QL'      | 'CHIP'         | ''          | ''   | '20200803'  
 '320NH/37A'                    | 'SMLF'     | 'IND'    | 'CV+32^0KZ14'(!)           = 'End of Design' | 'P/N Release'      | 'CV+32^0KZ14'              |'L_HCUVE768012-171_7-6X8-1'| '320NH/37A'                    | 'DISCRETE' | 'IND SMD 320NH 10% 37A(PGL6076.321HLT)'         | 'CHIP'         | ''          | ''   | '20200806'  
 '320NH/37A'                    | 'SMLF'     | 'EMPTY'  | 'CV+32^0KZ14'(!)           = 'End of Design' | 'P/N Release'      | 'CV+32^0KZ14'              |'L_HCUVE768012-171_7-6X8-1'| 'NA'                           | 'IO'       | 'IND SMD 320NH 10% 37A(PGL6076.321HLT)'         | 'CHIP'         | ''          | ''   | '20200806'  
 '10UH/15A'                     | 'THLF'     | 'IND'    | 'DC010F0M000'(!)           = ''              | ''                 | 'DC010F0M000'              |'LC36_P21XA'| '10UH/15A'                     | 'DISCRETE' | 'CHOKE 10UH +-20% 15A(PT20096L)'                | 'CHIP'         | ''          | ''   | '20200818'  
 '10UH/15A'                     | 'THLF'     | 'EMPTY'  | 'DC010F0M000'(!)           = ''              | ''                 | 'DC010F0M000'              |'LC36_P21XA'| 'NA'                           | 'IO'       | 'CHOKE 10UH +-20% 15A(PT20096L)'                | 'CHIP'         | ''          | ''   | '20200818'  
 '300NH/37A'                    | 'SMLF'     | 'IND'    | 'CV+30^0KZ18'(!)           = 'End of Design' | 'Comp-Approve'     | 'CV+30^0KZ18'              |'L_HCUVE966412D-221'| '300NH/37A'                    | 'DISCRETE' | 'IND SMD 300NH 10% 37A(PGL6216.301HLT)'         | 'CHIP'         | ''          | ''   | '20200824'  
 '300NH/37A'                    | 'SMLF'     | 'EMPTY'  | 'CV+30^0KZ18'(!)           = 'End of Design' | 'Comp-Approve'     | 'CV+30^0KZ18'              |'L_HCUVE966412D-221'| 'NA'                           | 'IO'       | 'IND SMD 300NH 10% 37A(PGL6216.301HLT)'         | 'CHIP'         | ''          | ''   | '20200824'  
 '270NH/49A'                    | 'SMLF'     | 'IND'    | 'CV+27^0KZ20'(!)           = ''              | ''                 | 'CV+27^0KZ20'              |'L_HCUVE966412D-221'| '270NH/49A'                    | 'DISCRETE' | 'IND SMD 270NH 10% 49A(PGL6216.271HLT)'         | 'CHIP'         | ''          | ''   | '20200824'  
 '270NH/49A'                    | 'SMLF'     | 'EMPTY'  | 'CV+27^0KZ20'(!)           = ''              | ''                 | 'CV+27^0KZ20'              |'L_HCUVE966412D-221'| 'NA'                           | 'IO'       | 'IND SMD 270NH 10% 49A(PGL6216.271HLT)'         | 'CHIP'         | ''          | ''   | '20200824'  
 '0.68UH/34A'                   | 'SMLF'     | 'IND'    | 'CV+68Z0MZ04'(!)           = ''              | ''                 | 'CV+68Z0MZ04'              |'L_CMME104T_10-1X10'| '0.68UH/34A'                   | 'DISCRETE' | 'IND SMD 0.68UH 20% 34A(CMME104T-R68MS1R6'      | 'CHIP'         | ''          | ''   | '20200827'  
 '0.68UH/34A'                   | 'SMLF'     | 'EMPTY'  | 'CV+68Z0MZ04'(!)           = ''              | ''                 | 'CV+68Z0MZ04'              |'L_CMME104T_10-1X10'| 'NA'                           | 'IO'       | 'IND SMD 0.68UH 20% 34A(CMME104T-R68MS1R6'      | 'CHIP'         | ''          | ''   | '20200827'  
 '39NH/200MA'                   | 'SMLF'     | 'IND'    | 'CVA3902JN00'(!)           = ''              | ''                 | 'CVA3902JN00'              |'L0402'| '39NH/200MA'                   | 'DISCRETE' | 'IND CHIP 39NH,+-5%,200MA,LQG15HS39NJ02D'       | 'CHIP'         | ''          | ''   | '20200914'  
 '39NH/200MA'                   | 'SMLF'     | 'EMPTY'  | 'CVA3902JN00'(!)           = ''              | ''                 | 'CVA3902JN00'              |'L0402'| 'NA'                           | 'IO'       | 'IND CHIP 39NH,+-5%,200MA,LQG15HS39NJ02D'       | 'CHIP'         | ''          | ''   | '20200914'  
 '2.7NH/0.55A'                  | 'SMLF'     | 'IND'    | 'CVB2706TN01'(!)           = ''              | ''                 | 'CVB2706TN01'              |'L0201'| '2.7NH/0.55A'                  | 'DISCRETE' | 'IND CHIP 2.7N+-0.1N0.55A(LQP03TQ2N7B02D)'      | 'CHIP'         | ''          | ''   | '20200916'  
 '2.7NH/0.55A'                  | 'SMLF'     | 'EMPTY'  | 'CVB2706TN01'(!)           = ''              | ''                 | 'CVB2706TN01'              |'L0201'| 'NA'                           | 'IO'       | 'IND CHIP 2.7N+-0.1N0.55A(LQP03TQ2N7B02D)'      | 'CHIP'         | ''          | ''   | '20200916'  
 '2.4NH/300MA'                  | 'SMLF'     | 'IND'    | 'CV-2403TZ00'(!)           = ''              | ''                 | 'CV-2403TZ00'              |'L0402'| '2.4NH/300MA'                  | 'DISCRETE' | 'IND SMD 2.4N ��0.3N 300MA LQG15HS2N4S02D'  | 'CHIP'         | ''          | ''   | '20200916'  
 '2.4NH/300MA'                  | 'SMLF'     | 'EMPTY'  | 'CV-2403TZ00'(!)           = ''              | ''                 | 'CV-2403TZ00'              |'L0402'| 'NA'                           | 'IO'       | 'IND SMD 2.4N ��0.3N 300MA LQG15HS2N4S02D'  | 'CHIP'         | ''          | ''   | '20200916'  
 '1.5NH/0.3A'                   | 'SMLF'     | 'IND'    | 'CVB1503TN01'(!)           = ''              | ''                 | 'CVB1503TN01'              |'L0402'| '1.5NH/0.3A'                   | 'DISCRETE' | 'IND CHIP 1.5N(+-0.3N,0.3A)LQG15HS1N5S02D'      | 'CHIP'         | ''          | ''   | '20200916'  
 '1.5NH/0.3A'                   | 'SMLF'     | 'EMPTY'  | 'CVB1503TN01'(!)           = ''              | ''                 | 'CVB1503TN01'              |'L0402'| 'NA'                           | 'IO'       | 'IND CHIP 1.5N(+-0.3N,0.3A)LQG15HS1N5S02D'      | 'CHIP'         | ''          | ''   | '20200916'  
 '18NH/300MA'                   | 'SMLF'     | 'IND'    | 'CVA1803JN02'(!)           = ''              | ''                 | 'CVA1803JN02'              |'L0402'| '18NH/300MA'                   | 'DISCRETE' | 'IND CHIP 18N +-5% 300MA,LQG15HS18NJ02D'        | 'CHIP'         | ''          | ''   | '20200916'  
 '18NH/300MA'                   | 'SMLF'     | 'EMPTY'  | 'CVA1803JN02'(!)           = ''              | ''                 | 'CVA1803JN02'              |'L0402'| 'NA'                           | 'IO'       | 'IND CHIP 18N +-5% 300MA,LQG15HS18NJ02D'        | 'CHIP'         | ''          | ''   | '20200916'  
 '2.2NH/300MA'                  | 'SMLF'     | 'IND'    | 'CVB2203TN02'(!)           = ''              | ''                 | 'CVB2203TN02'              |'L0402'| '2.2NH/300MA'                  | 'DISCRETE' | 'IND 2.2NH(+-0.3N,300MA)LQG15HS2N2S02D'         | 'CHIP'         | ''          | ''   | '20200916'  
 '2.2NH/300MA'                  | 'SMLF'     | 'EMPTY'  | 'CVB2203TN02'(!)           = ''              | ''                 | 'CVB2203TN02'              |'L0402'| 'NA'                           | 'IO'       | 'IND 2.2NH(+-0.3N,300MA)LQG15HS2N2S02D'         | 'CHIP'         | ''          | ''   | '20200916'  
 '1.8NH/0.3A'                   | 'SMLF'     | 'IND'    | 'CVB1803TN26'(!)           = ''              | ''                 | 'CVB1803TN26'              |'L0402'| '1.8NH/0.3A'                   | 'DISCRETE' | 'IND CHIP 1.8N(+-0.3N,0.3A)LQG15HS1N8S02D'      | 'CHIP'         | ''          | ''   | '20200916'  
 '1.8NH/0.3A'                   | 'SMLF'     | 'EMPTY'  | 'CVB1803TN26'(!)           = ''              | ''                 | 'CVB1803TN26'              |'L0402'| 'NA'                           | 'IO'       | 'IND CHIP 1.8N(+-0.3N,0.3A)LQG15HS1N8S02D'      | 'CHIP'         | ''          | ''   | '20200916'  
 '4.7UH/0.84A'                  | 'SMLF'     | 'IND'    | 'CV-4709TZ02'(!)           = ''              | ''                 | 'CV-4709TZ02'              |'L_MSCDRI4D28_H79'| '4.7UH/0.84A'                  | 'DISCRETE' | 'IND SMD 4.7UH 30% 0.84A MSCDRI-4D18-4R7N'      | 'CHIP'         | ''          | ''   | '20200918'  
 '4.7UH/0.84A'                  | 'SMLF'     | 'EMPTY'  | 'CV-4709TZ02'(!)           = ''              | ''                 | 'CV-4709TZ02'              |'L_MSCDRI4D28_H79'| 'NA'                           | 'IO'       | 'IND SMD 4.7UH 30% 0.84A MSCDRI-4D18-4R7N'      | 'CHIP'         | ''          | ''   | '20200918'  
 '82NH/400MA'                   | 'SMLF'     | 'IND'    | 'CVA8204GZ05'(!)           = ''              | ''                 | 'CVA8204GZ05'              |'L0805CSXA'| '82NH/400MA'                   | 'DISCRETE' | 'IND SMD 82NH 2% 400MA(0805CS-820EGTS)'         | 'CHIP'         | ''          | ''   | '20200924'  
 '82NH/400MA'                   | 'SMLF'     | 'EMPTY'  | 'CVA8204GZ05'(!)           = ''              | ''                 | 'CVA8204GZ05'              |'L0805CSXA'| 'NA'                           | 'IO'       | 'IND SMD 82NH 2% 400MA(0805CS-820EGTS)'         | 'CHIP'         | ''          | ''   | '20200924'  
 '4.7UH/6.5A'                   | 'SMLF'     | 'IND'    | 'CV-4765MZ00'(!)           = ''              | ''                 | 'CV-4765MZ00'              |'L_SC2511_6-5X6-5'| '4.7UH/6.5A'                   | 'DISCRETE' | 'IND SMD 4.7UH +-20% 6.5A(SC2511-4R7M)'         | 'CHIP'         | ''          | ''   | '20200924'  
 '4.7UH/6.5A'                   | 'SMLF'     | 'EMPTY'  | 'CV-4765MZ00'(!)           = ''              | ''                 | 'CV-4765MZ00'              |'L_SC2511_6-5X6-5'| 'NA'                           | 'IO'       | 'IND SMD 4.7UH +-20% 6.5A(SC2511-4R7M)'         | 'CHIP'         | ''          | ''   | '20200924'  
 '2.7NH/1A'                     | 'SMLF'     | 'IND'    | 'CVB2710TN00'(!)           = ''              | ''                 | 'CVB2710TN00'              |'L0603'| '2.7NH/1A'                     | 'DISCRETE' | 'IND CHIP 2.7NH +-0.3NH 1A(LQG18HN2N7S00D'      | 'CHIP'         | ''          | ''   | '20201015'  
 '2.7NH/1A'                     | 'SMLF'     | 'EMPTY'  | 'CVB2710TN00'(!)           = ''              | ''                 | 'CVB2710TN00'              |'L0603'| 'NA'                           | 'IO'       | 'IND CHIP 2.7NH +-0.3NH 1A(LQG18HN2N7S00D'      | 'CHIP'         | ''          | ''   | '20201015'  
 '250NH/42A'                    | 'SMLF'     | 'IND'    | 'CV+25^0KZ06'(!)           = ''              | ''                 | 'CV+25^0KZ06'              |'L_HCUVD6270_6-2X5-5XA'| '250NH/42A'                    | 'DISCRETE' | 'IND SMD 250NH 10% 42A(HCUVD6270Q-251AQL)'      | 'CHIP'         | ''          | ''   | '20201023'  
 '250NH/42A'                    | 'SMLF'     | 'EMPTY'  | 'CV+25^0KZ06'(!)           = ''              | ''                 | 'CV+25^0KZ06'              |'L_HCUVD6270_6-2X5-5XA'| 'NA'                           | 'IO'       | 'IND SMD 250NH 10% 42A(HCUVD6270Q-251AQL)'      | 'CHIP'         | ''          | ''   | '20201023'  
 '400NH/41A'                    | 'SMLF'     | 'IND'    | 'CV+40^0KZ08'(!)           = ''              | ''                 | 'CV+40^0KZ08'              |'L_HCUVE117512D'| '400NH/41A'                    | 'DISCRETE' | 'IND SMD 400NH 10% 41A(HCUVE117512Q)1MHZ'       | 'CHIP'         | ''          | ''   | '20201027'  
 '400NH/41A'                    | 'SMLF'     | 'EMPTY'  | 'CV+40^0KZ08'(!)           = ''              | ''                 | 'CV+40^0KZ08'              |'L_HCUVE117512D'| 'NA'                           | 'IO'       | 'IND SMD 400NH 10% 41A(HCUVE117512Q)1MHZ'       | 'CHIP'         | ''          | ''   | '20201027'  
 '120NH/69A'                    | 'SMLF'     | 'IND'    | 'CV+12^0EZ01'(!)           = ''              | ''                 | 'CV+12^0EZ01'              |'L_VLBU6565100T-R12L_6-5X6-5'| '120NH/69A'                    | 'DISCRETE' | 'IND SMD 120NH 15% 69A(PGL6312.121HLT)'         | 'CHIP'         | ''          | ''   | '20201029'  
 '120NH/69A'                    | 'SMLF'     | 'EMPTY'  | 'CV+12^0EZ01'(!)           = ''              | ''                 | 'CV+12^0EZ01'              |'L_VLBU6565100T-R12L_6-5X6-5'| 'NA'                           | 'IO'       | 'IND SMD 120NH 15% 69A(PGL6312.121HLT)'         | 'CHIP'         | ''          | ''   | '20201029'  
 '1.5UH/53A'                    | 'SMLF'     | 'IND'    | 'CV-15^0MZ02'(!)           = ''              | ''                 | 'CV-15^0MZ02'              |'L_EM-15AM17VG1-QS_14-3X12-9'| '1.5UH/53A'                    | 'DISCRETE' | 'IND SMD 1.5UH 20% 53A(EM-15AM17VG1-QS)'        | 'CHIP'         | ''          | ''   | '20201030'  
 '1.5UH/53A'                    | 'SMLF'     | 'EMPTY'  | 'CV-15^0MZ02'(!)           = ''              | ''                 | 'CV-15^0MZ02'              |'L_EM-15AM17VG1-QS_14-3X12-9'| 'NA'                           | 'IO'       | 'IND SMD 1.5UH 20% 53A(EM-15AM17VG1-QS)'        | 'CHIP'         | ''          | ''   | '20201030'  
 '0.12UH/69A'                   | 'SMLF'     | 'IND'    | 'CV+12^0EZ02'(!)           = ''              | ''                 | 'CV+12^0EZ02'              |'L_VLBU6565100T-R12L-1_6-5X6-5'| '0.12UH/69A'                   | 'DISCRETE' | 'IND SMD 0.12UH 15% 69A(VLBU6565100T-1'         | 'CHIP'         | ''          | ''   | '20201106'  
 '0.12UH/69A'                   | 'SMLF'     | 'EMPTY'  | 'CV+12^0EZ02'(!)           = ''              | ''                 | 'CV+12^0EZ02'              |'L_VLBU6565100T-R12L-1_6-5X6-5'| 'NA'                           | 'IO'       | 'IND SMD 0.12UH 15% 69A(VLBU6565100T-1'         | 'CHIP'         | ''          | ''   | '20201106'  
 '120NH/69A'                    | 'SMLF'     | 'IND'    | 'CV+12^0EZ03'(!)           = ''              | ''                 | 'CV+12^0EZ03'              |'L_VLBU6565100T-R12L-1_6-5X6-5'| '120NH/69A'                    | 'DISCRETE' | 'IND SMD 120NH 15% 69A(PGL6312.121AHLT)'        | 'CHIP'         | ''          | ''   | '20201109'  
 '120NH/69A'                    | 'SMLF'     | 'EMPTY'  | 'CV+12^0EZ03'(!)           = ''              | ''                 | 'CV+12^0EZ03'              |'L_VLBU6565100T-R12L-1_6-5X6-5'| 'NA'                           | 'IO'       | 'IND SMD 120NH 15% 69A(PGL6312.121AHLT)'        | 'CHIP'         | ''          | ''   | '20201109'  
 '220NH/40A'                    | 'SMLF'     | 'IND'    | 'CV+22^0EZ02'(!)           = ''              | ''                 | 'CV+22^0EZ02'              |'L_HCME0711Q-121LQL_7X6-7'| '220NH/40A'                    | 'DISCRETE' | 'IND SMD 220NH 15% 40A(HCME0711Q-221LQL)'       | 'CHIP'         | ''          | ''   | '20201116'  
 '220NH/40A'                    | 'SMLF'     | 'EMPTY'  | 'CV+22^0EZ02'(!)           = ''              | ''                 | 'CV+22^0EZ02'              |'L_HCME0711Q-121LQL_7X6-7'| 'NA'                           | 'IO'       | 'IND SMD 220NH 15% 40A(HCME0711Q-221LQL)'       | 'CHIP'         | ''          | ''   | '20201116'  
 '330NH/26A'                    | 'SMLF'     | 'IND'    | 'CV+33R0EZ00'(!)           = ''              | ''                 | 'CV+33R0EZ00'              |'L_HCME0711Q-121LQL_7X6-7'| '330NH/26A'                    | 'DISCRETE' | 'IND SMD 330NH 15% 26A(HCME0711Q-331LQL)'       | 'CHIP'         | ''          | ''   | '20201116'  
 '330NH/26A'                    | 'SMLF'     | 'EMPTY'  | 'CV+33R0EZ00'(!)           = ''              | ''                 | 'CV+33R0EZ00'              |'L_HCME0711Q-121LQL_7X6-7'| 'NA'                           | 'IO'       | 'IND SMD 330NH 15% 26A(HCME0711Q-331LQL)'       | 'CHIP'         | ''          | ''   | '20201116'  
 '120NH/105A'                   | 'SMLF'     | 'IND'    | 'CV+12^0KZ17'(!)           = 'End of Design' | 'Comp-Approve'     | 'CV+12^0KZ17'              |'L_PGL6054121HLT_10X6'| '120NH/105A'                   | 'DISCRETE' | 'IND SMD 120NH 10% 105A(PGL6054.121AHLT)'       | 'CHIP'         | ''          | ''   | '20201218'  
 '120NH/105A'                   | 'SMLF'     | 'EMPTY'  | 'CV+12^0KZ17'(!)           = 'End of Design' | 'Comp-Approve'     | 'CV+12^0KZ17'              |'L_PGL6054121HLT_10X6'| 'NA'                           | 'IO'       | 'IND SMD 120NH 10% 105A(PGL6054.121AHLT)'       | 'CHIP'         | ''          | ''   | '20201218'  
 '800NH/19A'                    | 'SMLF'     | 'IND'    | 'CV+80J0KZ01'(!)           = ''              | ''                 | 'CV+80J0KZ01'              |'L_HCUVD8095D-102KBQL_8X8'| '800NH/19A'                    | 'DISCRETE' | 'IND SMD 800NH 10% 19A(HCUVD8095-801BQL)'       | 'CHIP'         | ''          | ''   | '20201221'  
 '800NH/19A'                    | 'SMLF'     | 'EMPTY'  | 'CV+80J0KZ01'(!)           = ''              | ''                 | 'CV+80J0KZ01'              |'L_HCUVD8095D-102KBQL_8X8'| 'NA'                           | 'IO'       | 'IND SMD 800NH 10% 19A(HCUVD8095-801BQL)'       | 'CHIP'         | ''          | ''   | '20201221'  
 '0.36UH/25A'                   | 'SMLF'     | 'IND'    | 'CV+36Q0MZ07'(!)           = ''              | ''                 | 'CV+36Q0MZ07'              |'L_PCMS063T_6-6X6-6'| '0.36UH/25A'                   | 'DISCRETE' | 'IND SMD 0.36UH20%25A(CMME063T-R36MS)'          | 'CHIP'         | ''          | ''   | '20210108'  
 '0.36UH/25A'                   | 'SMLF'     | 'EMPTY'  | 'CV+36Q0MZ07'(!)           = ''              | ''                 | 'CV+36Q0MZ07'              |'L_PCMS063T_6-6X6-6'| 'NA'                           | 'IO'       | 'IND SMD 0.36UH20%25A(CMME063T-R36MS)'          | 'CHIP'         | ''          | ''   | '20210108'  
 '330NH/26A'                    | 'SMLF'     | 'IND'    | 'CV+33R0EZ01'(!)           = ''              | ''                 | 'CV+33R0EZ01'              |'L_HCME0711Q-121LQL_7X6-7'| '330NH/26A'                    | 'DISCRETE' | 'IND SMD 330NH 15% 26A(MSI-700711VD-R33L)'      | 'CHIP'         | ''          | ''   | '20210114'  
 '330NH/26A'                    | 'SMLF'     | 'EMPTY'  | 'CV+33R0EZ01'(!)           = ''              | ''                 | 'CV+33R0EZ01'              |'L_HCME0711Q-121LQL_7X6-7'| 'NA'                           | 'IO'       | 'IND SMD 330NH 15% 26A(MSI-700711VD-R33L)'      | 'CHIP'         | ''          | ''   | '20210114'  
 '220NH/81A'                    | 'SMLF'     | 'IND'    | 'CV+22^0KZ42'(!)           = 'End of Design' | 'Comp-Approve'     | 'CV+22^0KZ42'              |'L_HCUVE1112D-221_10-7X7-5'| '220NH/81A'                    | 'DISCRETE' | 'IND SMD 220NH 10% 81A(PG2290.221AHLT)'         | 'CHIP'         | ''          | ''   | '20210202'  
 '220NH/81A'                    | 'SMLF'     | 'EMPTY'  | 'CV+22^0KZ42'(!)           = 'End of Design' | 'Comp-Approve'     | 'CV+22^0KZ42'              |'L_HCUVE1112D-221_10-7X7-5'| 'NA'                           | 'IO'       | 'IND SMD 220NH 10% 81A(PG2290.221AHLT)'         | 'CHIP'         | ''          | ''   | '20210202'  
 '220NH/75A'                    | 'SMLF'     | 'IND'    | 'CV+22^0KZ43'(!)           = ''              | ''                 | 'CV+22^0KZ43'              |'L_HCUVE1112D-221_10-7X7-5'| '220NH/75A'                    | 'DISCRETE' | 'IND SMD 220NH 10% 75A(HCUVE117512Q-221QL'      | 'CHIP'         | ''          | ''   | '20210202'  
 '220NH/75A'                    | 'SMLF'     | 'EMPTY'  | 'CV+22^0KZ43'(!)           = ''              | ''                 | 'CV+22^0KZ43'              |'L_HCUVE1112D-221_10-7X7-5'| 'NA'                           | 'IO'       | 'IND SMD 220NH 10% 75A(HCUVE117512Q-221QL'      | 'CHIP'         | ''          | ''   | '20210202'  
 '3.3UH/9.6A'                   | 'SMLF'     | 'IND'    | 'CV-3396MZ00'(!)           = ''              | ''                 | 'CV-3396MZ00'              |'L_PCMS063T_6-6X6-6'| '3.3UH/9.6A'                   | 'DISCRETE' | 'IND SMD 3.3UH 20% 9.6A(CMMH063T-3R3MS)'        | 'CHIP'         | ''          | ''   | '20210219'  
 '3.3UH/9.6A'                   | 'SMLF'     | 'EMPTY'  | 'CV-3396MZ00'(!)           = ''              | ''                 | 'CV-3396MZ00'              |'L_PCMS063T_6-6X6-6'| 'NA'                           | 'IO'       | 'IND SMD 3.3UH 20% 9.6A(CMMH063T-3R3MS)'        | 'CHIP'         | ''          | ''   | '20210219'  
 '1UH/16.5A'                    | 'SMLF'     | 'IND'    | 'CV-10G5MZ01'(!)           = ''              | ''                 | 'CV-10G5MZ01'              |'L_PCMS063T_6-6X6-6'| '1UH/16.5A'                    | 'DISCRETE' | 'IND SMD 1UH 20% 16.5A(CMMH063T-1R0MS)'         | 'CHIP'         | ''          | ''   | '20210219'  
 '1UH/16.5A'                    | 'SMLF'     | 'EMPTY'  | 'CV-10G5MZ01'(!)           = ''              | ''                 | 'CV-10G5MZ01'              |'L_PCMS063T_6-6X6-6'| 'NA'                           | 'IO'       | 'IND SMD 1UH 20% 16.5A(CMMH063T-1R0MS)'         | 'CHIP'         | ''          | ''   | '20210219'  
 '0.33UH/26A'                   | 'SMLF'     | 'IND'    | 'CV+33R0MZ01'(!)           = ''              | ''                 | 'CV+33R0MZ01'              |'L_PCMS063T_6-6X6-6'| '0.33UH/26A'                   | 'DISCRETE' | 'IND SMD 0.33UH 20% 26A(CMMH063T-R33MS)'        | 'CHIP'         | ''          | ''   | '20210219'  
 '0.33UH/26A'                   | 'SMLF'     | 'EMPTY'  | 'CV+33R0MZ01'(!)           = ''              | ''                 | 'CV+33R0MZ01'              |'L_PCMS063T_6-6X6-6'| 'NA'                           | 'IO'       | 'IND SMD 0.33UH 20% 26A(CMMH063T-R33MS)'        | 'CHIP'         | ''          | ''   | '20210219'  
 '3.3UH/7.8A'                   | 'SMLF'     | 'IND'    | 'CV-3378MZ00'(!)           = ''              | ''                 | 'CV-3378MZ00'              |'L_HBMQ053T_5-25X5-2'| '3.3UH/7.8A'                   | 'DISCRETE' | 'IND SMD 3.3UH 20% 7.8A(HBMQ053T- 3R3MT)'       | 'CHIP'         | ''          | ''   | '20210219'  
 '3.3UH/7.8A'                   | 'SMLF'     | 'EMPTY'  | 'CV-3378MZ00'(!)           = ''              | ''                 | 'CV-3378MZ00'              |'L_HBMQ053T_5-25X5-2'| 'NA'                           | 'IO'       | 'IND SMD 3.3UH 20% 7.8A(HBMQ053T- 3R3MT)'       | 'CHIP'         | ''          | ''   | '20210219'  
 '0.12UH/69A'                   | 'SMLF'     | 'IND'    | 'CV+12^0EZ07'(!)           = ''              | ''                 | 'CV+12^0EZ07'              |'L_VLBU6565100T-R12L-1_6-5X6-5'| '0.12UH/69A'                   | 'DISCRETE' | 'IND SMD 0.12UH 15% 69A(VLBU6565100T-R12L'      | 'CHIP'         | ''          | ''   | '20210302'  
 '0.12UH/69A'                   | 'SMLF'     | 'EMPTY'  | 'CV+12^0EZ07'(!)           = ''              | ''                 | 'CV+12^0EZ07'              |'L_VLBU6565100T-R12L-1_6-5X6-5'| 'NA'                           | 'IO'       | 'IND SMD 0.12UH 15% 69A(VLBU6565100T-R12L'      | 'CHIP'         | ''          | ''   | '20210302'  
 '300NH/44A'                    | 'SMLF'     | 'IND'    | 'CV+30^0KZ19'(!)           = ''              | ''                 | 'CV+30^0KZ19'              |'L_HCUVE966412D-221'| '300NH/44A'                    | 'DISCRETE' | 'IND SMD 300NH 10% 44A(HCUVE966412Q-301QL'      | 'CHIP'         | ''          | ''   | '20210315'  
 '300NH/44A'                    | 'SMLF'     | 'EMPTY'  | 'CV+30^0KZ19'(!)           = ''              | ''                 | 'CV+30^0KZ19'              |'L_HCUVE966412D-221'| 'NA'                           | 'IO'       | 'IND SMD 300NH 10% 44A(HCUVE966412Q-301QL'      | 'CHIP'         | ''          | ''   | '20210315'  
 'BLM15PX471SN1D/1000MA'        | 'SMLF'     | 'IND'    | 'CX5PX471000'(!)           = ''              | ''                 | 'CX5PX471000'              |'L0402'| 'BLM15PX471SN1D/1000MA'        | 'DISCRETE' | 'EMI FILTER BLM15PX471SN1D (470,1000MA)'        | 'CHIP'         | ''          | ''   | '20210407'  
 'BLM15PX471SN1D/1000MA'        | 'SMLF'     | 'EMPTY'  | 'CX5PX471000'(!)           = ''              | ''                 | 'CX5PX471000'              |'L0402'| 'NA'                           | 'IO'       | 'EMI FILTER BLM15PX471SN1D (470,1000MA)'        | 'CHIP'         | ''          | ''   | '20210407'  
 'BLM15BB221SN1D/300MA'         | 'SMLF'     | 'IND'    | 'CX5BB221109'(!)           = ''              | ''                 | 'CX5BB221109'              |'L0402'| 'BLM15BB221SN1D/300MA'         | 'DISCRETE' | 'EMI FILTER BLM15BB221SN1D(220,300MA)'          | 'CHIP'         | ''          | ''   | '20210407'  
 'BLM15BB221SN1D/300MA'         | 'SMLF'     | 'EMPTY'  | 'CX5BB221109'(!)           = ''              | ''                 | 'CX5BB221109'              |'L0402'| 'NA'                           | 'IO'       | 'EMI FILTER BLM15BB221SN1D(220,300MA)'          | 'CHIP'         | ''          | ''   | '20210407'  
 '4.7UH/2A'                     | 'SMLF'     | 'IND'    | 'CV-4720MZ05'(!)           = ''              | ''                 | 'CV-4720MZ05'              |'L_BWVC004040184R7M00_4X4'| '4.7UH/2A'                     | 'DISCRETE' | 'IND SMD 4.7UH 20% 2A(BWVC004040184R7M00)'      | 'CHIP'         | ''          | ''   | '20210427'  
 '4.7UH/2A'                     | 'SMLF'     | 'EMPTY'  | 'CV-4720MZ05'(!)           = ''              | ''                 | 'CV-4720MZ05'              |'L_BWVC004040184R7M00_4X4'| 'NA'                           | 'IO'       | 'IND SMD 4.7UH 20% 2A(BWVC004040184R7M00)'      | 'CHIP'         | ''          | ''   | '20210427'  
 'BLM18KG121TN1D/3A'            | 'SMLF'     | 'IND'    | 'CX8KG121001'(!)           = ''              | ''                 | 'CX8KG121001'              |'L0603'| 'BLM18KG121TN1D/3A'            | 'DISCRETE' | 'EMI FILTER BLM18KG121TN1D(120,3A)'             | 'CHIP'         | ''          | ''   | '20210427'  
 'BLM18KG121TN1D/3A'            | 'SMLF'     | 'EMPTY'  | 'CX8KG121001'(!)           = ''              | ''                 | 'CX8KG121001'              |'L0603'| 'NA'                           | 'IO'       | 'EMI FILTER BLM18KG121TN1D(120,3A)'             | 'CHIP'         | ''          | ''   | '20210427'  
 '400NH/32A'                    | 'SMLF'     | 'IND'    | 'CV+40X0KZ00'(!)           = ''              | ''                 | 'CV+40X0KZ00'              |'L_HCUVE966412D-221'| '400NH/32A'                    | 'DISCRETE' | 'IND SMD 400NH 10% 32A(HCUVE966412Q-401QL'      | 'CHIP'         | ''          | ''   | '20210503'  
 '400NH/32A'                    | 'SMLF'     | 'EMPTY'  | 'CV+40X0KZ00'(!)           = ''              | ''                 | 'CV+40X0KZ00'              |'L_HCUVE966412D-221'| 'NA'                           | 'IO'       | 'IND SMD 400NH 10% 32A(HCUVE966412Q-401QL'      | 'CHIP'         | ''          | ''   | '20210503'  
 'BLM18PG330SN1D/3000M'         | 'SMLF'     | 'IND'    | 'CX8PG330007'(!)           = ''              | ''                 | 'CX8PG330007'              |'L0603'| 'BLM18PG330SN1D/3000M'         | 'DISCRETE' | 'FERRITE BEAD BLM18PG330SN1D (3000M)'           | 'CHIP'         | ''          | ''   | '20210505'  
 'BLM18PG330SN1D/3000M'         | 'SMLF'     | 'EMPTY'  | 'CX8PG330007'(!)           = ''              | ''                 | 'CX8PG330007'              |'L0603'| 'NA'                           | 'IO'       | 'FERRITE BEAD BLM18PG330SN1D (3000M)'           | 'CHIP'         | ''          | ''   | '20210505'  
 '120NH/69A'                    | 'SMLF'     | 'IND'    | 'CV+12^0EZ04'(!)           = ''              | ''                 | 'CV+12^0EZ04'              |'L_VLBU6565100T-R12L-1_6-5X6-5'| '120NH/69A'                    | 'DISCRETE' | 'IND SMD 120NH 15% 69A(HCME656510Q-121QL)'      | 'CHIP'         | ''          | ''   | '20210507'  
 '120NH/69A'                    | 'SMLF'     | 'EMPTY'  | 'CV+12^0EZ04'(!)           = ''              | ''                 | 'CV+12^0EZ04'              |'L_VLBU6565100T-R12L-1_6-5X6-5'| 'NA'                           | 'IO'       | 'IND SMD 120NH 15% 69A(HCME656510Q-121QL)'      | 'CHIP'         | ''          | ''   | '20210507'  
 '300NH/33A'                    | 'SMLF'     | 'IND'    | 'CV+30Y0KZ06'(!)           = ''              | ''                 | 'CV+30Y0KZ06'              |'L_HCUVE966490D-121'| '300NH/33A'                    | 'DISCRETE' | 'IND SMD 300NH 10% 33A(HCUVE966490Q-301QL'      | 'CHIP'         | ''          | ''   | '20210507'  
 '300NH/33A'                    | 'SMLF'     | 'EMPTY'  | 'CV+30Y0KZ06'(!)           = ''              | ''                 | 'CV+30Y0KZ06'              |'L_HCUVE966490D-121'| 'NA'                           | 'IO'       | 'IND SMD 300NH 10% 33A(HCUVE966490Q-301QL'      | 'CHIP'         | ''          | ''   | '20210507'  
 '3.3UH/10A'                    | 'SMLF'     | 'IND'    | 'CV-33A0MZ01'(!)           = ''              | ''                 | 'CV-33A0MZ01'              |'L_MMD-10DZ-R45M-X2Q'| '3.3UH/10A'                    | 'DISCRETE' | 'IND SMD 3.3UH20%10A(MMD-10DZ-3R3M-X2Q)'        | 'CHIP'         | ''          | ''   | '20210507'  
 '3.3UH/10A'                    | 'SMLF'     | 'EMPTY'  | 'CV-33A0MZ01'(!)           = ''              | ''                 | 'CV-33A0MZ01'              |'L_MMD-10DZ-R45M-X2Q'| 'NA'                           | 'IO'       | 'IND SMD 3.3UH20%10A(MMD-10DZ-3R3M-X2Q)'        | 'CHIP'         | ''          | ''   | '20210507'  
 'MHC1608P220Z06BP8A0/8A'       | 'SMLF'     | 'IND'    | 'CX220Z06Z00'(!)           = ''              | ''                 | 'CX220Z06Z00'              |'L0603'| 'MHC1608P220Z06BP8A0/8A'       | 'DISCRETE' | 'EMI FILTER MHC1608P220Z06BP8A0(22,8A)'         | 'CHIP'         | ''          | ''   | '20210507'  
 'MHC1608P220Z06BP8A0/8A'       | 'SMLF'     | 'EMPTY'  | 'CX220Z06Z00'(!)           = ''              | ''                 | 'CX220Z06Z00'              |'L0603'| 'NA'                           | 'IO'       | 'EMI FILTER MHC1608P220Z06BP8A0(22,8A)'         | 'CHIP'         | ''          | ''   | '20210507'  
 'BLM18SG330SN1D/5A'            | 'SMLF'     | 'IND'    | 'CX330SN1000'(!)           = ''              | ''                 | 'CX330SN1000'              |'L0603'| 'BLM18SG330SN1D/5A'            | 'DISCRETE' | 'EMI FILTER BEAD BLM18SG330SN1D(33,3.5A)'       | 'CHIP'         | ''          | ''   | '20210507'  
 'BLM18SG330SN1D/5A'            | 'SMLF'     | 'EMPTY'  | 'CX330SN1000'(!)           = ''              | ''                 | 'CX330SN1000'              |'L0603'| 'NA'                           | 'IO'       | 'EMI FILTER BEAD BLM18SG330SN1D(33,3.5A)'       | 'CHIP'         | ''          | ''   | '20210507'  
 '1UH/11A'                      | 'SMLF'     | 'IND'    | 'CV-10B0MZ47'(!)           = ''              | ''                 | 'CV-10B0MZ47'              |'L_DO3316H-102MLD_13-21X9-91'| '1UH/11A'                      | 'DISCRETE' | 'IND SMD 1UH 20% 11A(DO3316H-102MLD)AEC'        | 'CHIP'         | ''          | ''   | '20210511'  
 '1UH/11A'                      | 'SMLF'     | 'EMPTY'  | 'CV-10B0MZ47'(!)           = ''              | ''                 | 'CV-10B0MZ47'              |'L_DO3316H-102MLD_13-21X9-91'| 'NA'                           | 'IO'       | 'IND SMD 1UH 20% 11A(DO3316H-102MLD)AEC'        | 'CHIP'         | ''          | ''   | '20210511'  
 '68NH/69A'                     | 'SMLF'     | 'IND'    | 'CVA68^0KZ00'(!)           = ''              | ''                 | 'CVA68^0KZ00'              |'L_TPI078060L056N_7X8'| '68NH/69A'                     | 'DISCRETE' | 'IND SMD 68NH 10% 69A(TPI078060L068N)'          | 'CHIP'         | ''          | ''   | '20210511'  
 '68NH/69A'                     | 'SMLF'     | 'EMPTY'  | 'CVA68^0KZ00'(!)           = ''              | ''                 | 'CVA68^0KZ00'              |'L_TPI078060L056N_7X8'| 'NA'                           | 'IO'       | 'IND SMD 68NH 10% 69A(TPI078060L068N)'          | 'CHIP'         | ''          | ''   | '20210511'  
 '22UH/3.4A'                    | 'SMLF'     | 'IND'    | 'CV02234MZ00'(!)           = ''              | ''                 | 'CV02234MZ00'              |'L_XAL5050-223MEC_5-28X5-48'| '22UH/3.4A'                    | 'DISCRETE' | 'IND SMD 22U 20% 3.4A(XAL5050-223MEC)AEC'       | 'CHIP'         | ''          | ''   | '20210512'  
 '22UH/3.4A'                    | 'SMLF'     | 'EMPTY'  | 'CV02234MZ00'(!)           = ''              | ''                 | 'CV02234MZ00'              |'L_XAL5050-223MEC_5-28X5-48'| 'NA'                           | 'IO'       | 'IND SMD 22U 20% 3.4A(XAL5050-223MEC)AEC'       | 'CHIP'         | ''          | ''   | '20210512'  
 '150NH/75A'                    | 'SMLF'     | 'IND'    | 'CV+15^0KZ26'(!)           = ''              | ''                 | 'CV+15^0KZ26'              |'L_HCUVE966490D-121'| '150NH/75A'                    | 'DISCRETE' | 'IND SMD 150NH 10% 75A(HCUVE966490Q-151QL'      | 'CHIP'         | ''          | ''   | '20210514'  
 '150NH/75A'                    | 'SMLF'     | 'EMPTY'  | 'CV+15^0KZ26'(!)           = ''              | ''                 | 'CV+15^0KZ26'              |'L_HCUVE966490D-121'| 'NA'                           | 'IO'       | 'IND SMD 150NH 10% 75A(HCUVE966490Q-151QL'      | 'CHIP'         | ''          | ''   | '20210514'  
 '10UH/15A'                     | 'THLF'     | 'IND'    | 'DC010F0M002'(!)           = ''              | ''                 | 'DC010F0M002'              |'LC38_P21'| '10UH/15A'                     | 'DISCRETE' | 'CHOKE 10UH 20% 15A(ZT14C6C6F5D1100MAAC01'      | 'CHIP'         | ''          | ''   | '20210519'  
 '10UH/15A'                     | 'THLF'     | 'EMPTY'  | 'DC010F0M002'(!)           = ''              | ''                 | 'DC010F0M002'              |'LC38_P21'| 'NA'                           | 'IO'       | 'CHOKE 10UH 20% 15A(ZT14C6C6F5D1100MAAC01'      | 'CHIP'         | ''          | ''   | '20210519'  
 '47NH/0.3A'                    | 'SMLF'     | 'IND'    | 'CVA4703JZ03'(!)           = ''              | ''                 | 'CVA4703JZ03'              |'L0603_H40'| '47NH/0.3A'                    | 'DISCRETE' | 'IND SMD 47NH 5% 0.3A(HCI1608LF-47NJ)'          | 'CHIP'         | ''          | ''   | '20210519'  
 '47NH/0.3A'                    | 'SMLF'     | 'EMPTY'  | 'CVA4703JZ03'(!)           = ''              | ''                 | 'CVA4703JZ03'              |'L0603_H40'| 'NA'                           | 'IO'       | 'IND SMD 47NH 5% 0.3A(HCI1608LF-47NJ)'          | 'CHIP'         | ''          | ''   | '20210519'  
 '1.5UH/48A'                    | 'SMLF'     | 'IND'    | 'CV-15Z0MZ00'(!)           = ''              | ''                 | 'CV-15Z0MZ00'              |'L_HCM1305-1R5-R_13-3X12-2'| '1.5UH/48A'                    | 'DISCRETE' | 'IND SMD 1.5UH 20% 48A(HCM1305-1R5-R)'          | 'CHIP'         | ''          | ''   | '20210520'  
 '1.5UH/48A'                    | 'SMLF'     | 'EMPTY'  | 'CV-15Z0MZ00'(!)           = ''              | ''                 | 'CV-15Z0MZ00'              |'L_HCM1305-1R5-R_13-3X12-2'| 'NA'                           | 'IO'       | 'IND SMD 1.5UH 20% 48A(HCM1305-1R5-R)'          | 'CHIP'         | ''          | ''   | '20210520'  
 'HCB1608KF-330T60/6A'          | 'SMLF'     | 'IND'    | 'CX330T60002'(!)           = ''              | ''                 | 'CX330T60002'              |'L0603'| 'HCB1608KF-330T60/6A'          | 'DISCRETE' | 'EMI FILTER HCB1608KF-330T60(33,6A)'            | 'CHIP'         | ''          | ''   | '20210526'  
 'HCB1608KF-330T60/6A'          | 'SMLF'     | 'EMPTY'  | 'CX330T60002'(!)           = ''              | ''                 | 'CX330T60002'              |'L0603'| 'NA'                           | 'IO'       | 'EMI FILTER HCB1608KF-330T60(33,6A)'            | 'CHIP'         | ''          | ''   | '20210526'  
 'HCB3216KF-121T30/3A'          | 'SMLF'     | 'IND'    | 'CX121T30002'(!)           = 'End of Design' | 'Comp-Approve'     | 'CX121T30002'              |'L1206XH'| 'HCB3216KF-121T30/3A'          | 'DISCRETE' | 'EMI FILTER HCB3216KF-121T30(120,3A)'           | 'CHIP'         | ''          | ''   | '20210527'  
 'HCB3216KF-121T30/3A'          | 'SMLF'     | 'EMPTY'  | 'CX121T30002'(!)           = 'End of Design' | 'Comp-Approve'     | 'CX121T30002'              |'L1206XH'| 'NA'                           | 'IO'       | 'EMI FILTER HCB3216KF-121T30(120,3A)'           | 'CHIP'         | ''          | ''   | '20210527'  
 '6.8UH/3.6A'                   | 'SMLF'     | 'IND'    | 'CV-6836MZ00'(!)           = ''              | ''                 | 'CV-6836MZ00'              |'L_HPAL1V0530-6R8-R_5-4X5-2'| '6.8UH/3.6A'                   | 'DISCRETE' | 'IND SMD 6.8U 20% 3.6A(HPAL1V0530-6R8-R)'       | 'CHIP'         | ''          | ''   | '20210527'  
 '6.8UH/3.6A'                   | 'SMLF'     | 'EMPTY'  | 'CV-6836MZ00'(!)           = ''              | ''                 | 'CV-6836MZ00'              |'L_HPAL1V0530-6R8-R_5-4X5-2'| 'NA'                           | 'IO'       | 'IND SMD 6.8U 20% 3.6A(HPAL1V0530-6R8-R)'       | 'CHIP'         | ''          | ''   | '20210527'  
 '2.2UH/7A'                     | 'SMLF'     | 'IND'    | 'CV-2270MZ24'(!)           = ''              | ''                 | 'CV-2270MZ24'              |'L_HPAL1V0530-6R8-R_5-4X5-2'| '2.2UH/7A'                     | 'DISCRETE' | 'IND SMD 2.2U 20% 7A(HPAL1V0530-2R2-R)'         | 'CHIP'         | ''          | ''   | '20210527'  
 '2.2UH/7A'                     | 'SMLF'     | 'EMPTY'  | 'CV-2270MZ24'(!)           = ''              | ''                 | 'CV-2270MZ24'              |'L_HPAL1V0530-6R8-R_5-4X5-2'| 'NA'                           | 'IO'       | 'IND SMD 2.2U 20% 7A(HPAL1V0530-2R2-R)'         | 'CHIP'         | ''          | ''   | '20210527'  
 '3.3UH/7.8A'                   | 'SMLF'     | 'IND'    | 'CV-3378MZ01'(!)           = ''              | ''                 | 'CV-3378MZ01'              |'L_HBMQ053T_5-25X5-2'| '3.3UH/7.8A'                   | 'DISCRETE' | 'IND SMD 3.3UH 20% 7.8A(HBMQ053T-3R3MT)'        | 'CHIP'         | ''          | ''   | '20210531'  
 '3.3UH/7.8A'                   | 'SMLF'     | 'EMPTY'  | 'CV-3378MZ01'(!)           = ''              | ''                 | 'CV-3378MZ01'              |'L_HBMQ053T_5-25X5-2'| 'NA'                           | 'IO'       | 'IND SMD 3.3UH 20% 7.8A(HBMQ053T-3R3MT)'        | 'CHIP'         | ''          | ''   | '20210531'  
 '0.8UH/37.8A'                  | 'SMLF'     | 'IND'    | 'CV+80^8MZ00'(!)           = ''              | ''                 | 'CV+80^8MZ00'              |'L_XAL7070-801MEC_7-2X7-5'| '0.8UH/37.8A'                  | 'DISCRETE' | 'IND SMD0.8UH20% 37.8A(XAL7070-801MEC)AEC'      | 'CHIP'         | ''          | ''   | '20210531'  
 '0.8UH/37.8A'                  | 'SMLF'     | 'EMPTY'  | 'CV+80^8MZ00'(!)           = ''              | ''                 | 'CV+80^8MZ00'              |'L_XAL7070-801MEC_7-2X7-5'| 'NA'                           | 'IO'       | 'IND SMD0.8UH20% 37.8A(XAL7070-801MEC)AEC'      | 'CHIP'         | ''          | ''   | '20210531'  
 '1000NH/17A'                   | 'SMLF'     | 'IND'    | 'CV-10H0KZ04'(!)           = ''              | ''                 | 'CV-10H0KZ04'              |'L_HCUVD8095D-102KBQL_8X8'| '1000NH/17A'                   | 'DISCRETE' | 'IND SMD 1000NH 10% 17A(HCUVD8095Q-102BQL'      | 'CHIP'         | ''          | ''   | '20210601'  
 '1000NH/17A'                   | 'SMLF'     | 'EMPTY'  | 'CV-10H0KZ04'(!)           = ''              | ''                 | 'CV-10H0KZ04'              |'L_HCUVD8095D-102KBQL_8X8'| 'NA'                           | 'IO'       | 'IND SMD 1000NH 10% 17A(HCUVD8095Q-102BQL'      | 'CHIP'         | ''          | ''   | '20210601'  
 '800NH/22A'                    | 'SMLF'     | 'IND'    | 'CV+80M0KZ00'(!)           = ''              | ''                 | 'CV+80M0KZ00'              |'L_HCUVD8095D-102KBQL_8X8'| '800NH/22A'                    | 'DISCRETE' | 'IND SMD 800NH 10% 22A(HCUVD8095Q-801BQL)'      | 'CHIP'         | ''          | ''   | '20210601'  
 '800NH/22A'                    | 'SMLF'     | 'EMPTY'  | 'CV+80M0KZ00'(!)           = ''              | ''                 | 'CV+80M0KZ00'              |'L_HCUVD8095D-102KBQL_8X8'| 'NA'                           | 'IO'       | 'IND SMD 800NH 10% 22A(HCUVD8095Q-801BQL)'      | 'CHIP'         | ''          | ''   | '20210601'  
 'HCB1005KF-101T20/2A'          | 'SMLF'     | 'IND'    | 'CX101T20001'(!)           = ''              | ''                 | 'CX101T20001'              |'L0402_H24'| 'HCB1005KF-101T20/2A'          | 'DISCRETE' | 'EMI FILTER BEAD HCB1005KF-101T20(100,2A)'      | 'CHIP'         | ''          | ''   | '20210624'  
 'HCB1005KF-101T20/2A'          | 'SMLF'     | 'EMPTY'  | 'CX101T20001'(!)           = ''              | ''                 | 'CX101T20001'              |'L0402_H24'| 'NA'                           | 'IO'       | 'EMI FILTER BEAD HCB1005KF-101T20(100,2A)'      | 'CHIP'         | ''          | ''   | '20210624'  
 '0.15UH/38A'                   | 'SMLF'     | 'IND'    | 'CV+15^0MZ63'(!)           = ''              | ''                 | 'CV+15^0MZ63'              |'L_HBTD053T-R15MS_5-1X5-3'| '0.15UH/38A'                   | 'DISCRETE' | 'IND SMD 0.15UH 20%38A(HBTD053T-R15MS)'         | 'CHIP'         | ''          | ''   | '20210624'  
 '0.15UH/38A'                   | 'SMLF'     | 'EMPTY'  | 'CV+15^0MZ63'(!)           = ''              | ''                 | 'CV+15^0MZ63'              |'L_HBTD053T-R15MS_5-1X5-3'| 'NA'                           | 'IO'       | 'IND SMD 0.15UH 20%38A(HBTD053T-R15MS)'         | 'CHIP'         | ''          | ''   | '20210624'  
 '0.24UH/33A'                   | 'SMLF'     | 'IND'    | 'CV+24Y0MZ00'(!)           = ''              | ''                 | 'CV+24Y0MZ00'              |'L_HBTD053T-R24MS_5-1X5-3'| '0.24UH/33A'                   | 'DISCRETE' | 'IND SMD 0.24UH 20% 33A(HBTD053T-R24MS)'        | 'CHIP'         | ''          | ''   | '20210624'  
 '0.24UH/33A'                   | 'SMLF'     | 'EMPTY'  | 'CV+24Y0MZ00'(!)           = ''              | ''                 | 'CV+24Y0MZ00'              |'L_HBTD053T-R24MS_5-1X5-3'| 'NA'                           | 'IO'       | 'IND SMD 0.24UH 20% 33A(HBTD053T-R24MS)'        | 'CHIP'         | ''          | ''   | '20210624'  
 '4.7NH/850MA'                  | 'SMLF'     | 'IND'    | 'CVB4709TN00'(!)           = ''              | ''                 | 'CVB4709TN00'              |'L0603_H40'| '4.7NH/850MA'                  | 'DISCRETE' | 'INDCHIP 4.7N(+-0.5N 850MA) LQW18AN4N7D00'      | 'CHIP'         | ''          | ''   | '20210701'  
 '4.7NH/850MA'                  | 'SMLF'     | 'EMPTY'  | 'CVB4709TN00'(!)           = ''              | ''                 | 'CVB4709TN00'              |'L0603_H40'| 'NA'                           | 'IO'       | 'INDCHIP 4.7N(+-0.5N 850MA) LQW18AN4N7D00'      | 'CHIP'         | ''          | ''   | '20210701'  
 '1.0UH/2.1A'                   | 'SMLF'     | 'IND'    | 'CV-1021TZ02'(!)           = ''              | ''                 | 'CV-1021TZ02'              | 'L_1226AS-H_3X2-8'                | '1.0UH/2.1A'                   | 'DISCRETE' | 'IND SMD 1.0UH 30% 2.1A(1226AS-H-1R0N=P2)'      | 'CHIP'         | ''          | ''   | '20210708'  
 '1.0UH/2.1A'                   | 'SMLF'     | 'EMPTY'  | 'CV-1021TZ02'(!)           = ''              | ''                 | 'CV-1021TZ02'              | 'L_1226AS-H_3X2-8'                | 'NA'                           | 'IO'       | 'IND SMD 1.0UH 30% 2.1A(1226AS-H-1R0N=P2)'      | 'CHIP'         | ''          | ''   | '20210708'  
 'BPH323023W5-400T/15A'         | 'SMLF'     | 'IND'    | 'CX323023000'(!)           = ''              | ''                 | 'CX323023000'              |'L_BPH323023W5-400T_3-08X2-9'| 'BPH323023W5-400T/15A'         | 'DISCRETE' | 'EMI FILTER BEAD BPH323023W5-400T(40,15A)'      | 'CHIP'         | ''          | ''   | '20210720'  
 'BPH323023W5-400T/15A'         | 'SMLF'     | 'EMPTY'  | 'CX323023000'(!)           = ''              | ''                 | 'CX323023000'              |'L_BPH323023W5-400T_3-08X2-9'| 'NA'                           | 'IO'       | 'EMI FILTER BEAD BPH323023W5-400T(40,15A)'      | 'CHIP'         | ''          | ''   | '20210720'  
 '120NH/82A'                    | 'SMLF'     | 'IND'    | 'CV+12^0KZ20'(!)           = ''              | ''                 | 'CV+12^0KZ20'              |'L_HCUVD6270_6-2X5-5XA'| '120NH/82A'                    | 'DISCRETE' | 'IND SMD 120NH 10% 82A(HCUVD6270GQ-121AQL'      | 'CHIP'         | ''          | ''   | '20210720'  
 '120NH/82A'                    | 'SMLF'     | 'EMPTY'  | 'CV+12^0KZ20'(!)           = ''              | ''                 | 'CV+12^0KZ20'              |'L_HCUVD6270_6-2X5-5XA'| 'NA'                           | 'IO'       | 'IND SMD 120NH 10% 82A(HCUVD6270GQ-121AQL'      | 'CHIP'         | ''          | ''   | '20210720'  
 'MPZ1608S600AT/3.5A'           | 'SMLF'     | 'IND'    | 'CX08S600001'(!)           = ''              | 'End of Life'      | 'CX08S600001'              |'L0603_EOL'| 'MPZ1608S600AT/3.5A'           | 'DISCRETE' | 'EMI FILTER MPZ1608S600AT(60,3.5A,0.02)EP'      | 'CHIP'         | ''          | ''   | '20210730'  
 'MPZ1608S600AT/3.5A'           | 'SMLF'     | 'EMPTY'  | 'CX08S600001'(!)           = ''              | 'End of Life'      | 'CX08S600001'              |'L0603_EOL'| 'NA'                           | 'IO'       | 'EMI FILTER MPZ1608S600AT(60,3.5A,0.02)EP'      | 'CHIP'         | ''          | ''   | '20210730'  
 '1UH/2.1A'                     | 'SMLF'     | 'IND'    | 'CV-1021TZ00'(!)           = ''              | ''                 | 'CV-1021TZ00'              |'L_NR3015T_3X3'| '1UH/2.1A'                     | 'DISCRETE' | 'IND SMD 1UH +-30% 2.1A(NR3015T1R0N)'           | 'CHIP'         | ''          | ''   | '20210730'  
 '1UH/2.1A'                     | 'SMLF'     | 'EMPTY'  | 'CV-1021TZ00'(!)           = ''              | ''                 | 'CV-1021TZ00'              |'L_NR3015T_3X3'| 'NA'                           | 'IO'       | 'IND SMD 1UH +-30% 2.1A(NR3015T1R0N)'           | 'CHIP'         | ''          | ''   | '20210730'  
 'BLM15BD221SN1D/300MA'         | 'SMLF'     | 'IND'    | 'CX5BD221000'(!)           = ''              | ''                 | 'CX5BD221000'              |'L0402'| 'BLM15BD221SN1D/300MA'         | 'DISCRETE' | 'EMI FILTER BLM15BD221SN1D(220,300MA)'          | 'CHIP'         | ''          | ''   | '20210730'  
 'BLM15BD221SN1D/300MA'         | 'SMLF'     | 'EMPTY'  | 'CX5BD221000'(!)           = ''              | ''                 | 'CX5BD221000'              |'L0402'| 'NA'                           | 'IO'       | 'EMI FILTER BLM15BD221SN1D(220,300MA)'          | 'CHIP'         | ''          | ''   | '20210730'  
 'BLM21SP700SN1D/6A'            | 'SMLF'     | 'IND'    | 'CX700SN1002'(!)           = ''              | ''                 | 'CX700SN1002'              |'L0805'| 'BLM21SP700SN1D/6A'            | 'DISCRETE' | 'EMI FILTER BLM21SP700SN1D(70,6A)'              | 'CHIP'         | ''          | ''   | '20210802'  
 'BLM21SP700SN1D/6A'            | 'SMLF'     | 'EMPTY'  | 'CX700SN1002'(!)           = ''              | ''                 | 'CX700SN1002'              |'L0805'| 'NA'                           | 'IO'       | 'EMI FILTER BLM21SP700SN1D(70,6A)'              | 'CHIP'         | ''          | ''   | '20210802'  
 '4.7UH/710MA'                  | 'SMLF'     | 'IND'    | 'CV-4708MN00'(!)           = ''              | ''                 | 'CV-4708MN00'              |'L_SWF3225CF-4R7M_3-6X2-8'| '4.7UH/710MA'                  | 'DISCRETE' | 'IND CHIP 4.7UH 20%,710MA(SWF3225CF-4R7M)'      | 'CHIP'         | ''          | ''   | '20210805'  
 '4.7UH/710MA'                  | 'SMLF'     | 'EMPTY'  | 'CV-4708MN00'(!)           = ''              | ''                 | 'CV-4708MN00'              |'L_SWF3225CF-4R7M_3-6X2-8'| 'NA'                           | 'IO'       | 'IND CHIP 4.7UH 20%,710MA(SWF3225CF-4R7M)'      | 'CHIP'         | ''          | ''   | '20210805'  
 '0.6UH/2.8A'                   | 'SMLF'     | 'IND'    | 'CV+6028MZ01'(!)           = ''              | ''                 | 'CV+6028MZ01'              |'L_XFL4012_4X4'| '0.6UH/2.8A'                   | 'DISCRETE' | 'IND SMD 0.6UH 20% 2.8A(XFL4012-601MEC)'        | 'CHIP'         | ''          | ''   | '20210817'  
 '0.6UH/2.8A'                   | 'SMLF'     | 'EMPTY'  | 'CV+6028MZ01'(!)           = ''              | ''                 | 'CV+6028MZ01'              |'L_XFL4012_4X4'| 'NA'                           | 'IO'       | 'IND SMD 0.6UH 20% 2.8A(XFL4012-601MEC)'        | 'CHIP'         | ''          | ''   | '20210817'  
 '1.0UH/4.3A'                   | 'SMLF'     | 'IND'    | 'CV-1043MZ07'(!)           = ''              | ''                 | 'CV-1043MZ07'              |'L_NR3015T_3X3_H48'| '1.0UH/4.3A'                   | 'DISCRETE' | 'IND SMD 1.0UH 20% 4.3A(MDMK3030T1R0MM)'        | 'CHIP'         | ''          | ''   | '20210824'  
 '1.0UH/4.3A'                   | 'SMLF'     | 'EMPTY'  | 'CV-1043MZ07'(!)           = ''              | ''                 | 'CV-1043MZ07'              |'L_NR3015T_3X3_H48'| 'NA'                           | 'IO'       | 'IND SMD 1.0UH 20% 4.3A(MDMK3030T1R0MM)'        | 'CHIP'         | ''          | ''   | '20210824'  
 'BLM31KN121SN1L/6A'            | 'SMLF'     | 'IND'    | 'CX1KN121000'(!)           = 'End of Design' | 'Comp-Approve'     | 'CX1KN121000'              |'L1206XA'| 'BLM31KN121SN1L/6A'            | 'DISCRETE' | 'EMI FILTER BEAD BLM31KN121SN1L(120,6A)'        | 'CHIP'         | ''          | ''   | '20210825'  
 'BLM31KN121SN1L/6A'            | 'SMLF'     | 'EMPTY'  | 'CX1KN121000'(!)           = 'End of Design' | 'Comp-Approve'     | 'CX1KN121000'              |'L1206XA'| 'NA'                           | 'IO'       | 'EMI FILTER BEAD BLM31KN121SN1L(120,6A)'        | 'CHIP'         | ''          | ''   | '20210825'  
 'GMLB-160808-0600P-N8/1A'      | 'SMLF'     | 'IND'    | 'CX080600029'(!)           = ''              | ''                 | 'CX080600029'              |'L0603'| 'GMLB-160808-0600P-N8/1A'      | 'DISCRETE' | 'EMI FILTER GMLB-160808-0600P-N8(600,1A)'       | 'CHIP'         | ''          | ''   | '20210902'  
 'GMLB-160808-0600P-N8/1A'      | 'SMLF'     | 'EMPTY'  | 'CX080600029'(!)           = ''              | ''                 | 'CX080600029'              |'L0603'| 'NA'                           | 'IO'       | 'EMI FILTER GMLB-160808-0600P-N8(600,1A)'       | 'CHIP'         | ''          | ''   | '20210902'  
 '0.07UH/166A'                  | 'SMLF'     | 'IND'    | 'CVA70^0EZ00'(!)           = ''              | ''                 | 'CVA70^0EZ00'              |'L_HCME1012Q-700QL_10X6-2'| '0.07UH/166A'                  | 'DISCRETE' | 'IND SMD 0.07UH 15% 166A(HCME1012Q-700QL)'      | 'CHIP'         | ''          | ''   | '20210914'  
 '0.07UH/166A'                  | 'SMLF'     | 'EMPTY'  | 'CVA70^0EZ00'(!)           = ''              | ''                 | 'CVA70^0EZ00'              |'L_HCME1012Q-700QL_10X6-2'| 'NA'                           | 'IO'       | 'IND SMD 0.07UH 15% 166A(HCME1012Q-700QL)'      | 'CHIP'         | ''          | ''   | '20210914'  
 '470NH/27A'                    | 'SMLF'     | 'IND'    | 'CV+47S0KZ00'(!)           = ''              | ''                 | 'CV+47S0KZ00'              |'L_HCUVE966412D-221'| '470NH/27A'                    | 'DISCRETE' | 'IND SMD 470NH 10% 27A(HCUVE966412Q-471QL'      | 'CHIP'         | ''          | ''   | '20210915'  
 '470NH/27A'                    | 'SMLF'     | 'EMPTY'  | 'CV+47S0KZ00'(!)           = ''              | ''                 | 'CV+47S0KZ00'              |'L_HCUVE966412D-221'| 'NA'                           | 'IO'       | 'IND SMD 470NH 10% 27A(HCUVE966412Q-471QL'      | 'CHIP'         | ''          | ''   | '20210915'  
 '220NH/33A'                    | 'SMLF'     | 'IND'    | 'CV+22Y0EZ01'(!)           = ''              | ''                 | 'CV+22Y0EZ01'              |'L_VLBU6565100T-R12L-1_6-5X6-5'| '220NH/33A'                    | 'DISCRETE' | 'IND SMD 220NH 15% 33A(PGL6312.221AHLT)'        | 'CHIP'         | ''          | ''   | '20210915'  
 '220NH/33A'                    | 'SMLF'     | 'EMPTY'  | 'CV+22Y0EZ01'(!)           = ''              | ''                 | 'CV+22Y0EZ01'              |'L_VLBU6565100T-R12L-1_6-5X6-5'| 'NA'                           | 'IO'       | 'IND SMD 220NH 15% 33A(PGL6312.221AHLT)'        | 'CHIP'         | ''          | ''   | '20210915'  
 '3NH/0.67A'                    | 'SMLF'     | 'IND'    | 'CVB3007TN00'(!)           = ''              | ''                 | 'CVB3007TN00'              |'L0603_W1-1'| '3NH/0.67A'                    | 'DISCRETE' | 'IND CHIP 3NH+-0.2NH 0.67A(LQW18AN3N0C80)'      | 'CHIP'         | ''          | ''   | '20210922'  
 '3NH/0.67A'                    | 'SMLF'     | 'EMPTY'  | 'CVB3007TN00'(!)           = ''              | ''                 | 'CVB3007TN00'              |'L0603_W1-1'| 'NA'                           | 'IO'       | 'IND CHIP 3NH+-0.2NH 0.67A(LQW18AN3N0C80)'      | 'CHIP'         | ''          | ''   | '20210922'  
 '90NH/155A'                    | 'SMLF'     | 'IND'    | 'CVA90^0KZ13'(!)           = 'End of Design' | 'Comp-Approve'     | 'CVA90^0KZ13'              |'L_HCME107512Q-900QL_10X7-7'| '90NH/155A'                    | 'DISCRETE' | 'IND SMD 90NH 10% 155A(PG2323.900HLT)'          | 'CHIP'         | ''          | ''   | '20210923'  
 '90NH/155A'                    | 'SMLF'     | 'EMPTY'  | 'CVA90^0KZ13'(!)           = 'End of Design' | 'Comp-Approve'     | 'CVA90^0KZ13'              |'L_HCME107512Q-900QL_10X7-7'| 'NA'                           | 'IO'       | 'IND SMD 90NH 10% 155A(PG2323.900HLT)'          | 'CHIP'         | ''          | ''   | '20210923'  
 '0.22UH/33A'                   | 'SMLF'     | 'IND'    | 'CV+22Y0EZ00'(!)           = ''              | ''                 | 'CV+22Y0EZ00'              |'L_VLBU6565100T-R12L-1_6-5X6-5'| '0.22UH/33A'                   | 'DISCRETE' | 'IND SMD 0.22UH 15% 33A(HCME656510Q-221QL'      | 'CHIP'         | ''          | ''   | '20210928'  
 '0.22UH/33A'                   | 'SMLF'     | 'EMPTY'  | 'CV+22Y0EZ00'(!)           = ''              | ''                 | 'CV+22Y0EZ00'              |'L_VLBU6565100T-R12L-1_6-5X6-5'| 'NA'                           | 'IO'       | 'IND SMD 0.22UH 15% 33A(HCME656510Q-221QL'      | 'CHIP'         | ''          | ''   | '20210928'  
 '470NH/22A'                    | 'SMLF'     | 'IND'    | 'CV+47M0KZ00'(!)           = ''              | ''                 | 'CV+47M0KZ00'              |'L_HCUVD6270_6-2X5-5XA'| '470NH/22A'                    | 'DISCRETE' | 'IND SMD470NH 10% 22ADC(HCUVD6270Q-471AQL'      | 'CHIP'         | ''          | ''   | '20211110'  
 '470NH/22A'                    | 'SMLF'     | 'EMPTY'  | 'CV+47M0KZ00'(!)           = ''              | ''                 | 'CV+47M0KZ00'              |'L_HCUVD6270_6-2X5-5XA'| 'NA'                           | 'IO'       | 'IND SMD470NH 10% 22ADC(HCUVD6270Q-471AQL'      | 'CHIP'         | ''          | ''   | '20211110'  
 '220NH/47A'                    | 'SMLF'     | 'IND'    | 'CV+22^0KZ46'(!)           = ''              | ''                 | 'CV+22^0KZ46'              |'L_HCUVD6270_6-2X5-5XA'| '220NH/47A'                    | 'DISCRETE' | 'IND SMD220NH 10% 47ADC(HCUVD6270Q-221AQL'      | 'CHIP'         | ''          | ''   | '20211110'  
 '220NH/47A'                    | 'SMLF'     | 'EMPTY'  | 'CV+22^0KZ46'(!)           = ''              | ''                 | 'CV+22^0KZ46'              |'L_HCUVD6270_6-2X5-5XA'| 'NA'                           | 'IO'       | 'IND SMD220NH 10% 47ADC(HCUVD6270Q-221AQL'      | 'CHIP'         | ''          | ''   | '20211110'  
 '180NH/60A'                    | 'SMLF'     | 'IND'    | 'CV+18^0KZ23'(!)           = ''              | ''                 | 'CV+18^0KZ23'              |'L_HCUVD6270_6-2X5-5XA'| '180NH/60A'                    | 'DISCRETE' | 'IND SMD180NH 10% 60ADC(HCUVD6270Q-181AQL'      | 'CHIP'         | ''          | ''   | '20211110'  
 '180NH/60A'                    | 'SMLF'     | 'EMPTY'  | 'CV+18^0KZ23'(!)           = ''              | ''                 | 'CV+18^0KZ23'              |'L_HCUVD6270_6-2X5-5XA'| 'NA'                           | 'IO'       | 'IND SMD180NH 10% 60ADC(HCUVD6270Q-181AQL'      | 'CHIP'         | ''          | ''   | '20211110'  
 '1UH/3.1A'                     | 'SMLF'     | 'IND'    | 'CV-1031MN01'(!)           = ''              | ''                 | 'CV-1031MN01'              |'L_DFE201610E_2X1-6'| '1UH/3.1A'                     | 'DISCRETE' | 'IND CHIP 1UH +-20% 3.1A DFE201610E-1R0MC'      | 'CHIP'         | ''          | ''   | '20211124'  
 '1UH/3.1A'                     | 'SMLF'     | 'EMPTY'  | 'CV-1031MN01'(!)           = ''              | ''                 | 'CV-1031MN01'              |'L_DFE201610E_2X1-6'| 'NA'                           | 'IO'       | 'IND CHIP 1UH +-20% 3.1A DFE201610E-1R0MC'      | 'CHIP'         | ''          | ''   | '20211124'  
 'BLM21SP331SN1D/1.9A'          | 'SMLF'     | 'IND'    | 'CX331SN1000'(!)           = ''              | ''                 | 'CX331SN1000'              |'L0805'| 'BLM21SP331SN1D/1.9A'          | 'DISCRETE' | 'EMI FILTER BLM21SP331SN1D(330,1.9A)'           | 'CHIP'         | ''          | ''   | '20211201'  
 'BLM21SP331SN1D/1.9A'          | 'SMLF'     | 'EMPTY'  | 'CX331SN1000'(!)           = ''              | ''                 | 'CX331SN1000'              |'L0805'| 'NA'                           | 'IO'       | 'EMI FILTER BLM21SP331SN1D(330,1.9A)'           | 'CHIP'         | ''          | ''   | '20211201'  
 '1UH/4A'                       | 'SMLF'     | 'IND'    | 'CV-1040MZ13'(!)           = ''              | 'P/N Release'      | 'CV-1040MZ13'              | 'L_DFE201610E_2X1-6_H48'          | '1UH/4A'                       | 'DISCRETE' | 'IND SMD 1UH 20% 4A (DFE201612E-1R0M=P2)'       | 'CHIP'         | ''          | ''   | '20211201'  
 '1UH/4A'                       | 'SMLF'     | 'EMPTY'  | 'CV-1040MZ13'(!)           = ''              | 'P/N Release'      | 'CV-1040MZ13'              | 'L_DFE201610E_2X1-6_H48'          | 'NA'                           | 'IO'       | 'IND SMD 1UH 20% 4A (DFE201612E-1R0M=P2)'       | 'CHIP'         | ''          | ''   | '20211201'  
 '120NH/65A'                    | 'SMLF'     | 'IND'    | 'CV+12^0KZ00'(!)           = ''              | ''                 | 'CV+12^0KZ00'              |'L_HCB106480N'| '120NH/65A'                    | 'DISCRETE' | 'IND SMD 120NH +/-10% 65A(HCB106480N-121)'      | 'CHIP'         | ''          | ''   | '20211209'  
 '120NH/65A'                    | 'SMLF'     | 'EMPTY'  | 'CV+12^0KZ00'(!)           = ''              | ''                 | 'CV+12^0KZ00'              |'L_HCB106480N'| 'NA'                           | 'IO'       | 'IND SMD 120NH +/-10% 65A(HCB106480N-121)'      | 'CHIP'         | ''          | ''   | '20211209'  
 '300NH/26A'                    | 'SMLF'     | 'IND'    | 'CV+30R0KZ00'(!)           = ''              | ''                 | 'CV+30R0KZ00'              |'L_HCB106480N'| '300NH/26A'                    | 'DISCRETE' | 'IND SMD 300NH +/-10% 26A(HCB106480N-301)'      | 'CHIP'         | ''          | ''   | '20211210'  
 '300NH/26A'                    | 'SMLF'     | 'EMPTY'  | 'CV+30R0KZ00'(!)           = ''              | ''                 | 'CV+30R0KZ00'              |'L_HCB106480N'| 'NA'                           | 'IO'       | 'IND SMD 300NH +/-10% 26A(HCB106480N-301)'      | 'CHIP'         | ''          | ''   | '20211210'  
 '120NH/94A'                    | 'SMLF'     | 'IND'    | 'CV+12^0KZ18'(!)           = ''              | ''                 | 'CV+12^0KZ18'              |'L_HCUVE966490D-121'| '120NH/94A'                    | 'DISCRETE' | 'IND SMD 120NH 10% 94A(HCUVE966490Q-121QL'      | 'CHIP'         | ''          | ''   | '20211210'  
 '120NH/94A'                    | 'SMLF'     | 'EMPTY'  | 'CV+12^0KZ18'(!)           = ''              | ''                 | 'CV+12^0KZ18'              |'L_HCUVE966490D-121'| 'NA'                           | 'IO'       | 'IND SMD 120NH 10% 94A(HCUVE966490Q-121QL'      | 'CHIP'         | ''          | ''   | '20211210'  
 'BLM15HG601SN1D/300MA'         | 'SMLF'     | 'IND'    | 'CX5HG601000'(!)           = ''              | ''                 | 'CX5HG601000'              |'L0402'| 'BLM15HG601SN1D/300MA'         | 'DISCRETE' | 'EMI FILTER BLM15HG601SN1D (600,300MA)'         | 'CHIP'         | ''          | ''   | '20211214'  
 'BLM15HG601SN1D/300MA'         | 'SMLF'     | 'EMPTY'  | 'CX5HG601000'(!)           = ''              | ''                 | 'CX5HG601000'              |'L0402'| 'NA'                           | 'IO'       | 'EMI FILTER BLM15HG601SN1D (600,300MA)'         | 'CHIP'         | ''          | ''   | '20211214'  
 '210NH/47A'                    | 'SMLF'     | 'IND'    | 'CV+21^0KZ05'(!)           = ''              | ''                 | 'CV+21^0KZ05'              |'L_HCUVE966490D-121'| '210NH/47A'                    | 'DISCRETE' | 'IND SMD 210NH 10% 47A(HCUVE966490Q-211QL'      | 'CHIP'         | ''          | ''   | '20211213'  
 '210NH/47A'                    | 'SMLF'     | 'EMPTY'  | 'CV+21^0KZ05'(!)           = ''              | ''                 | 'CV+21^0KZ05'              |'L_HCUVE966490D-121'| 'NA'                           | 'IO'       | 'IND SMD 210NH 10% 47A(HCUVE966490Q-211QL'      | 'CHIP'         | ''          | ''   | '20211213'  
 '0.47UH/23A'                   | 'SMLF'     | 'IND'    | 'CV+47N0KZ04'(!)           = ''              | ''                 | 'CV+47N0KZ04'              |'L_HCUVD6270_6-2X5-5XA'| '0.47UH/23A'                   | 'DISCRETE' | 'IND SMD 0.47UH 10%23A (MSI-600607VD-R47K'      | 'CHIP'         | ''          | ''   | '20211217'  
 '0.47UH/23A'                   | 'SMLF'     | 'EMPTY'  | 'CV+47N0KZ04'(!)           = ''              | ''                 | 'CV+47N0KZ04'              |'L_HCUVD6270_6-2X5-5XA'| 'NA'                           | 'IO'       | 'IND SMD 0.47UH 10%23A (MSI-600607VD-R47K'      | 'CHIP'         | ''          | ''   | '20211217'  
 '0.56UH/40A'                   | 'SMLF'     | 'IND'    | 'CV+56^0MZ08'(!)           = ''              | ''                 | 'CV+56^0MZ08'              |'L_MAC-10DZ_11-5X10'| '0.56UH/40A'                   | 'DISCRETE' | 'IND SMD 0.56UH20% 40A(HPCL1V1040-R56-R)'       | 'CHIP'         | ''          | ''   | '20211229'  
 '0.56UH/40A'                   | 'SMLF'     | 'EMPTY'  | 'CV+56^0MZ08'(!)           = ''              | ''                 | 'CV+56^0MZ08'              |'L_MAC-10DZ_11-5X10'| 'NA'                           | 'IO'       | 'IND SMD 0.56UH20% 40A(HPCL1V1040-R56-R)'       | 'CHIP'         | ''          | ''   | '20211229'  
 '5.6NH/1.9A'                   | 'SMLF'     | 'IND'    | 'CVB5619TN00'(!)           = ''              | ''                 | 'CVB5619TN00'              |'L0603_W1-1'| '5.6NH/1.9A'                   | 'DISCRETE' | 'IND CHIP 5.6NH+-0.2NH1.9A LQW18AN5N6C80D'      | 'CHIP'         | ''          | ''   | '20220105'  
 '5.6NH/1.9A'                   | 'SMLF'     | 'EMPTY'  | 'CVB5619TN00'(!)           = ''              | ''                 | 'CVB5619TN00'              |'L0603_W1-1'| 'NA'                           | 'IO'       | 'IND CHIP 5.6NH+-0.2NH1.9A LQW18AN5N6C80D'      | 'CHIP'         | ''          | ''   | '20220105'  
 '2.2NH/3.2A'                   | 'SMLF'     | 'IND'    | 'CVB2232TN00'(!)           = ''              | ''                 | 'CVB2232TN00'              |'L0603_W1-1'| '2.2NH/3.2A'                   | 'DISCRETE' | 'IND CHIP 2.2NH+-0.2NH3.2A LQW18AN2N2C80D'      | 'CHIP'         | ''          | ''   | '20220113'  
 '2.2NH/3.2A'                   | 'SMLF'     | 'EMPTY'  | 'CVB2232TN00'(!)           = ''              | ''                 | 'CVB2232TN00'              |'L0603_W1-1'| 'NA'                           | 'IO'       | 'IND CHIP 2.2NH+-0.2NH3.2A LQW18AN2N2C80D'      | 'CHIP'         | ''          | ''   | '20220113'  
 '2.2UH/8.3A'                   | 'SMLF'     | 'IND'    | 'CV-2283MZ02'(!)           = ''              | ''                 | 'CV-2283MZ02'              |'L_PCMS063T_6-6X6-6_H79'| '2.2UH/8.3A'                   | 'DISCRETE' | 'IND SMD 2.2UH +-20%8.3A(CMME062T-2R2MS)'       | 'CHIP'         | ''          | ''   | '20220207'  
 '2.2UH/8.3A'                   | 'SMLF'     | 'EMPTY'  | 'CV-2283MZ02'(!)           = ''              | ''                 | 'CV-2283MZ02'              |'L_PCMS063T_6-6X6-6_H79'| 'NA'                           | 'IO'       | 'IND SMD 2.2UH +-20%8.3A(CMME062T-2R2MS)'       | 'CHIP'         | ''          | ''   | '20220207'  
 '180NH/95A'                    | 'SMLF'     | 'IND'    | 'CV+18^0KZ24'(!)           = ''              | ''                 | 'CV+18^0KZ24'              |'L_HCUVE1112D-221_10-7X7-5'| '180NH/95A'                    | 'DISCRETE' | 'IND SMD 180NH 10% 95A(HCUVE117512-181RS'       | 'CHIP'         | ''          | ''   | '20220223'  
 '180NH/95A'                    | 'SMLF'     | 'EMPTY'  | 'CV+18^0KZ24'(!)           = ''              | ''                 | 'CV+18^0KZ24'              |'L_HCUVE1112D-221_10-7X7-5'| 'NA'                           | 'IO'       | 'IND SMD 180NH 10% 95A(HCUVE117512-181RS'       | 'CHIP'         | ''          | ''   | '20220223'  
 'HI0805R800R-10/5A'            | 'SMLF'     | 'IND'    | 'CX0R800R000'(!)           = ''              | ''                 | 'CX0R800R000'              |'L0805_H44'| 'HI0805R800R-10/5A'            | 'DISCRETE' | 'EMI FILTER HI0805R800R-10(80,5A)'              | 'CHIP'         | ''          | ''   | '20220224'  
 'HI0805R800R-10/5A'            | 'SMLF'     | 'EMPTY'  | 'CX0R800R000'(!)           = ''              | ''                 | 'CX0R800R000'              |'L0805_H44'| 'NA'                           | 'IO'       | 'EMI FILTER HI0805R800R-10(80,5A)'              | 'CHIP'         | ''          | ''   | '20220224'  
 '1UH/3A'                       | 'SMLF'     | 'IND'    | 'CV-1030MZ02'(!)           = ''              | ''                 | 'CV-1030MZ02'              | 'L_DFE252012C'                    | '1UH/3A'                       | 'DISCRETE' | 'IND SMD 1U +-20% 3A(1239AS-H-1R0M=P2)'         | 'CHIP'         | ''          | ''   | '20220311'  
 '1UH/3A'                       | 'SMLF'     | 'EMPTY'  | 'CV-1030MZ02'(!)           = ''              | ''                 | 'CV-1030MZ02'              | 'L_DFE252012C'                    | 'NA'                           | 'IO'       | 'IND SMD 1U +-20% 3A(1239AS-H-1R0M=P2)'         | 'CHIP'         | ''          | ''   | '20220311'  
 '0.1UH/28.5A'                  | 'SMLF'     | 'IND'    | 'CV+10T5MZ01'(!)           = ''              | ''                 | 'CV+10T5MZ01'              |'L_XAL4020-222MEC'| '0.1UH/28.5A'                  | 'DISCRETE' | 'IND SMD 0.1UH 20% 28.5A(MND-04BAIR10M-XH'      | 'CHIP'         | ''          | ''   | '20220314'  
 '0.1UH/28.5A'                  | 'SMLF'     | 'EMPTY'  | 'CV+10T5MZ01'(!)           = ''              | ''                 | 'CV+10T5MZ01'              |'L_XAL4020-222MEC'| 'NA'                           | 'IO'       | 'IND SMD 0.1UH 20% 28.5A(MND-04BAIR10M-XH'      | 'CHIP'         | ''          | ''   | '20220314'  
 '100NH/123A'                   | 'SMLF'     | 'IND'    | 'CV+10^0EZ06'(!)           = ''              | ''                 | 'CV+10^0EZ06'              |'L_HCME1012Q-121QL_10X6'| '100NH/123A'                   | 'DISCRETE' | 'IND SMD 100NH 15% 123A(HCME1012Q-101QL)'       | 'CHIP'         | ''          | ''   | '20220318'  
 '100NH/123A'                   | 'SMLF'     | 'EMPTY'  | 'CV+10^0EZ06'(!)           = ''              | ''                 | 'CV+10^0EZ06'              |'L_HCME1012Q-121QL_10X6'| 'NA'                           | 'IO'       | 'IND SMD 100NH 15% 123A(HCME1012Q-101QL)'       | 'CHIP'         | ''          | ''   | '20220318'  
 '0.22UH/29A'                   | 'SMLF'     | 'IND'    | 'CV+22U0MZ00'(!)           = ''              | ''                 | 'CV+22U0MZ00'              |'L_HBTD043T-R22MS_4-1X4-1'| '0.22UH/29A'                   | 'DISCRETE' | 'IND SMD 0.22U 20% 29A(HBTD043T-R22MS)'         | 'CHIP'         | ''          | ''   | '20220329'  
 '0.22UH/29A'                   | 'SMLF'     | 'EMPTY'  | 'CV+22U0MZ00'(!)           = ''              | ''                 | 'CV+22U0MZ00'              |'L_HBTD043T-R22MS_4-1X4-1'| 'NA'                           | 'IO'       | 'IND SMD 0.22U 20% 29A(HBTD043T-R22MS)'         | 'CHIP'         | ''          | ''   | '20220329'  
 '0.22UH/26A'                   | 'SMLF'     | 'IND'    | 'CV+22R0MZ00'(!)           = ''              | ''                 | 'CV+22R0MZ00'              |'L_PCMS063T_6-6X6-6'| '0.22UH/26A'                   | 'DISCRETE' | 'IND SMD 0.22UH +-20%26A(CMMS063T-R22MS)'       | 'CHIP'         | ''          | ''   | '20220411'  
 '0.22UH/26A'                   | 'SMLF'     | 'EMPTY'  | 'CV+22R0MZ00'(!)           = ''              | ''                 | 'CV+22R0MZ00'              |'L_PCMS063T_6-6X6-6'| 'NA'                           | 'IO'       | 'IND SMD 0.22UH +-20%26A(CMMS063T-R22MS)'       | 'CHIP'         | ''          | ''   | '20220411'  
 '0.47UH/30A'                   | 'SMLF'     | 'IND'    | 'CV+47V0MZ03'(!)           = ''              | ''                 | 'CV+47V0MZ03'              |'L_PCMS063T_6-6X6-6'| '0.47UH/30A'                   | 'DISCRETE' | 'IND SMD 0.47UH  20% 30A(CMMS063T-R47MS)'       | 'CHIP'         | ''          | ''   | '20220411'  
 '0.47UH/30A'                   | 'SMLF'     | 'EMPTY'  | 'CV+47V0MZ03'(!)           = ''              | ''                 | 'CV+47V0MZ03'              |'L_PCMS063T_6-6X6-6'| 'NA'                           | 'IO'       | 'IND SMD 0.47UH  20% 30A(CMMS063T-R47MS)'       | 'CHIP'         | ''          | ''   | '20220411'  
 'BBUPWN160805260Y00/6A'        | 'SMLF'     | 'IND'    | 'CX05260Y000'(!)           = ''              | ''                 | 'CX05260Y000'              |'L0603_H26'| 'BBUPWN160805260Y00/6A'        | 'DISCRETE' | 'EMI FILTER BBUPWN160805260Y00(26,6A)'          | 'CHIP'         | ''          | ''   | '20220412'  
 'BBUPWN160805260Y00/6A'        | 'SMLF'     | 'EMPTY'  | 'CX05260Y000'(!)           = ''              | ''                 | 'CX05260Y000'              |'L0603_H26'| 'NA'                           | 'IO'       | 'EMI FILTER BBUPWN160805260Y00(26,6A)'          | 'CHIP'         | ''          | ''   | '20220412'  
 '6.8UH/4A'                     | 'SMLF'     | 'IND'    | 'CV-6840MZ00'(!)           = ''              | ''                 | 'CV-6840MZ00'              |'L_PCMB062D'| '6.8UH/4A'                     | 'DISCRETE' | 'IND SMD 6.8UH +-20% 4A PCMB062D-6R8MS'         | 'CHIP'         | ''          | ''   | '20220413'  
 '6.8UH/4A'                     | 'SMLF'     | 'EMPTY'  | 'CV-6840MZ00'(!)           = ''              | ''                 | 'CV-6840MZ00'              |'L_PCMB062D'| 'NA'                           | 'IO'       | 'IND SMD 6.8UH +-20% 4A PCMB062D-6R8MS'         | 'CHIP'         | ''          | ''   | '20220413'  
 '150NH/120A'                   | 'SMLF'     | 'IND'    | 'CV+15^0KZ30'(!)           = ''              | ''                 | 'CV+15^0KZ30'              |'L_HCUVD8095D-102KBQL_8X8'| '150NH/120A'                   | 'DISCRETE' | 'IND SMD 150NH 10% 120A(HCUVD8095G-151QL)'      | 'CHIP'         | ''          | ''   | '20220421'  
 '150NH/120A'                   | 'SMLF'     | 'EMPTY'  | 'CV+15^0KZ30'(!)           = ''              | ''                 | 'CV+15^0KZ30'              |'L_HCUVD8095D-102KBQL_8X8'| 'NA'                           | 'IO'       | 'IND SMD 150NH 10% 120A(HCUVD8095G-151QL)'      | 'CHIP'         | ''          | ''   | '20220421'  
 '2.2UH/16A'                    | 'SMLF'     | 'IND'    | 'CV-22G0MZ09'(!)           = ''              | ''                 | 'CV-22G0MZ09'              |'L_PCMS063T_6-6X6-6'| '2.2UH/16A'                    | 'DISCRETE' | 'IND SMD 2.2UH 20% 16A(CMMS063T-2R2MS)'         | 'CHIP'         | ''          | ''   | '20220421'  
 '2.2UH/16A'                    | 'SMLF'     | 'EMPTY'  | 'CV-22G0MZ09'(!)           = ''              | ''                 | 'CV-22G0MZ09'              |'L_PCMS063T_6-6X6-6'| 'NA'                           | 'IO'       | 'IND SMD 2.2UH 20% 16A(CMMS063T-2R2MS)'         | 'CHIP'         | ''          | ''   | '20220421'  
 'PBY160808T-121Y-N/2.5A'       | 'SMLF'     | 'IND'    | 'CX08T121001'(!)           = ''              | ''                 | 'CX08T121001'              |'L0603'| 'PBY160808T-121Y-N/2.5A'       | 'DISCRETE' | 'EMI FILTER PBY160808T-121Y-N(120,2.5A)'        | 'CHIP'         | ''          | ''   | '20220422'  
 'PBY160808T-121Y-N/2.5A'       | 'SMLF'     | 'EMPTY'  | 'CX08T121001'(!)           = ''              | ''                 | 'CX08T121001'              |'L0603'| 'NA'                           | 'IO'       | 'EMI FILTER PBY160808T-121Y-N(120,2.5A)'        | 'CHIP'         | ''          | ''   | '20220422'  
 '700NH/62A'                    | 'SMLF'     | 'IND'    | 'CV+70^0KZ01'(!)           = ''              | ''                 | 'CV+70^0KZ01'              |'L_HCUVD1115_11X8XA'| '700NH/62A'                    | 'DISCRETE' | 'IND SMD 700NH 10% 62A(HCUVD1115-701QL)'        | 'CHIP'         | ''          | ''   | '20220428'  
 '700NH/62A'                    | 'SMLF'     | 'EMPTY'  | 'CV+70^0KZ01'(!)           = ''              | ''                 | 'CV+70^0KZ01'              |'L_HCUVD1115_11X8XA'| 'NA'                           | 'IO'       | 'IND SMD 700NH 10% 62A(HCUVD1115-701QL)'        | 'CHIP'         | ''          | ''   | '20220428'  
 'HCB1005KF-121T20/2000MA'      | 'SMLF'     | 'IND'    | 'CX121T20005'(!)           = ''              | ''                 | 'CX121T20005'              |'L0402_H24'| 'HCB1005KF-121T20/2000MA'      | 'DISCRETE' | 'EMI FILTER HCB1005KF-121T20(120,2000MA)'       | 'CHIP'         | ''          | ''   | '20220504'  
 'HCB1005KF-121T20/2000MA'      | 'SMLF'     | 'EMPTY'  | 'CX121T20005'(!)           = ''              | ''                 | 'CX121T20005'              |'L0402_H24'| 'NA'                           | 'IO'       | 'EMI FILTER HCB1005KF-121T20(120,2000MA)'       | 'CHIP'         | ''          | ''   | '20220504'  
 'HCB1608KF-121T30/3A'          | 'SMLF'     | 'IND'    | 'CX121T30000'(!)           = ''              | ''                 | 'CX121T30000'              |'L0603'| 'HCB1608KF-121T30/3A'          | 'DISCRETE' | 'EMI FILTER HCB1608KF-121T30(120+-25%,3A)'      | 'CHIP'         | ''          | ''   | '20220504'  
 'HCB1608KF-121T30/3A'          | 'SMLF'     | 'EMPTY'  | 'CX121T30000'(!)           = ''              | ''                 | 'CX121T30000'              |'L0603'| 'NA'                           | 'IO'       | 'EMI FILTER HCB1608KF-121T30(120+-25%,3A)'      | 'CHIP'         | ''          | ''   | '20220504'  
 '1.0UH/24A'                    | 'SMLF'     | 'IND'    | 'CV-10P0MZ08'(!)           = ''              | ''                 | 'CV-10P0MZ08'              |'L_MHD-07EZP_7-2X7-5'| '1.0UH/24A'                    | 'DISCRETE' | 'IND SMD 1.0UH 20% 24A(HM-10AM34VG1-QS)'        | 'CHIP'         | ''          | ''   | '20220505'  
 '1.0UH/24A'                    | 'SMLF'     | 'EMPTY'  | 'CV-10P0MZ08'(!)           = ''              | ''                 | 'CV-10P0MZ08'              |'L_MHD-07EZP_7-2X7-5'| 'NA'                           | 'IO'       | 'IND SMD 1.0UH 20% 24A(HM-10AM34VG1-QS)'        | 'CHIP'         | ''          | ''   | '20220505'  
 'GMLB-201209-0600Y-PY-QU/2A'   | 'SMLF'     | 'IND'    | 'CX090600002'(!)           = ''              | ''                 | 'CX090600002'              |'L0805_H44'| 'GMLB-201209-0600Y-PY-QU/2A'   | 'DISCRETE' | 'EMI FIL GMLB-201209-0600Y-PY-QU (600,2A)'      | 'CHIP'         | ''          | ''   | '20220602'  
 'GMLB-201209-0600Y-PY-QU/2A'   | 'SMLF'     | 'EMPTY'  | 'CX090600002'(!)           = ''              | ''                 | 'CX090600002'              |'L0805_H44'| 'NA'                           | 'IO'       | 'EMI FIL GMLB-201209-0600Y-PY-QU (600,2A)'      | 'CHIP'         | ''          | ''   | '20220602'  
 'BLE32PN300SN1L/10A'           | 'SMLF'     | 'IND'    | 'CX000300000'(!)           = ''              | ''                 | 'CX000300000'              |'L1210XD'| 'BLE32PN300SN1L/10A'           | 'DISCRETE' | 'EMI FILTER BLE32PN300SN1L(30,10A)'             | 'CHIP'         | ''          | ''   | '20220607'  
 'BLE32PN300SN1L/10A'           | 'SMLF'     | 'EMPTY'  | 'CX000300000'(!)           = ''              | ''                 | 'CX000300000'              |'L1210XD'| 'NA'                           | 'IO'       | 'EMI FILTER BLE32PN300SN1L(30,10A)'             | 'CHIP'         | ''          | ''   | '20220607'  
 '220NH/57A'                    | 'SMLF'     | 'IND'    | 'CV+22^0KZ41'(!)           = ''              | ''                 | 'CV+22^0KZ41'              |'L_HCUVE768012-171_7-6X8-1'| '220NH/57A'                    | 'DISCRETE' | 'IND SMD 220NH 10% 57A(HCUVE768012Q-221QL'      | 'CHIP'         | ''          | ''   | '20220607'  
 '220NH/57A'                    | 'SMLF'     | 'EMPTY'  | 'CV+22^0KZ41'(!)           = ''              | ''                 | 'CV+22^0KZ41'              |'L_HCUVE768012-171_7-6X8-1'| 'NA'                           | 'IO'       | 'IND SMD 220NH 10% 57A(HCUVE768012Q-221QL'      | 'CHIP'         | ''          | ''   | '20220607'  
 'BLM15PX331SN1D/1200MA'        | 'SMLF'     | 'IND'    | 'CX5PX331000'(!)           = ''              | ''                 | 'CX5PX331000'              |'L0402'| 'BLM15PX331SN1D/1200MA'        | 'DISCRETE' | 'EMI FILTER BLM15PX331SN1D (330,1200MA)'        | 'CHIP'         | ''          | ''   | '20220609'  
 'BLM15PX331SN1D/1200MA'        | 'SMLF'     | 'EMPTY'  | 'CX5PX331000'(!)           = ''              | ''                 | 'CX5PX331000'              |'L0402'| 'NA'                           | 'IO'       | 'EMI FILTER BLM15PX331SN1D (330,1200MA)'        | 'CHIP'         | ''          | ''   | '20220609'  
 '10UH/23A'                     | 'THLF'     | 'IND'    | 'DC010N0L001'(!)           = ''              | ''                 | 'DC010N0L001'              |'LC_P9W4-3_22X14'| '10UH/23A'                     | 'DISCRETE' | 'CHOKE 10UH 15% 23A(PSC-210160-100 GP'          | 'CHIP'         | ''          | ''   | '20220615'  
 '10UH/23A'                     | 'THLF'     | 'EMPTY'  | 'DC010N0L001'(!)           = ''              | ''                 | 'DC010N0L001'              |'LC_P9W4-3_22X14'| 'NA'                           | 'IO'       | 'CHOKE 10UH 15% 23A(PSC-210160-100 GP'          | 'CHIP'         | ''          | ''   | '20220615'  
 'BLM18KG101TN1D/3A'            | 'SMLF'     | 'IND'    | 'CX8KG101000'(!)           = ''              | ''                 | 'CX8KG101000'              |'L0603'| 'BLM18KG101TN1D/3A'            | 'DISCRETE' | 'EMI FILTER BLM18KG101TN1D (100,3A,0.03)'       | 'CHIP'         | ''          | ''   | '20220624'  
 'BLM18KG101TN1D/3A'            | 'SMLF'     | 'EMPTY'  | 'CX8KG101000'(!)           = ''              | ''                 | 'CX8KG101000'              |'L0603'| 'NA'                           | 'IO'       | 'EMI FILTER BLM18KG101TN1D (100,3A,0.03)'       | 'CHIP'         | ''          | ''   | '20220624'  
 '220NH/42A'                    | 'SMLF'     | 'IND'    | 'CV+22^0KZ50'(!)           = ''              | ''                 | 'CV+22^0KZ50'              |'L_HCME0711Q-221QL_7X6-7'| '220NH/42A'                    | 'DISCRETE' | 'IND SMD 220NH 10% 42A HCME0711Q-221QL'         | 'CHIP'         | ''          | ''   | '20220705'  
 '220NH/42A'                    | 'SMLF'     | 'EMPTY'  | 'CV+22^0KZ50'(!)           = ''              | ''                 | 'CV+22^0KZ50'              |'L_HCME0711Q-221QL_7X6-7'| 'NA'                           | 'IO'       | 'IND SMD 220NH 10% 42A HCME0711Q-221QL'         | 'CHIP'         | ''          | ''   | '20220705'  
 'BBPY00100505102Y00/500MA'     | 'SMLF'     | 'IND'    | 'CX505102000'(!)           = ''              | ''                 | 'CX505102000'              |'L0402_H24'| 'BBPY00100505102Y00/500MA'     | 'DISCRETE' | 'EMI FILTER BBPY00100505102(1K,500MA)SELA'      | 'CHIP'         | ''          | ''   | '20220715'  
 'BBPY00100505102Y00/500MA'     | 'SMLF'     | 'EMPTY'  | 'CX505102000'(!)           = ''              | ''                 | 'CX505102000'              |'L0402_H24'| 'NA'                           | 'IO'       | 'EMI FILTER BBPY00100505102(1K,500MA)SELA'      | 'CHIP'         | ''          | ''   | '20220715'  
 'HCB2012KF-121T25/2.5A'        | 'SMLF'     | 'IND'    | 'CX121T25000'(!)           = ''              | ''                 | 'CX121T25000'              |'L0805'| 'HCB2012KF-121T25/2.5A'        | 'DISCRETE' | 'EMI FILTER HCB2012KF-121T25(120,2.5A)'         | 'CHIP'         | ''          | ''   | '20220808'  
 'HCB2012KF-121T25/2.5A'        | 'SMLF'     | 'EMPTY'  | 'CX121T25000'(!)           = ''              | ''                 | 'CX121T25000'              |'L0805'| 'NA'                           | 'IO'       | 'EMI FILTER HCB2012KF-121T25(120,2.5A)'         | 'CHIP'         | ''          | ''   | '20220808'  
 '0.68UH/17A'                   | 'SMLF'     | 'IND'    | 'CV+68H0MZ03'(!)           = ''              | ''                 | 'CV+68H0MZ03'              |'L_PCMS063T_6-6X6-6_H79'| '0.68UH/17A'                   | 'DISCRETE' | 'IND SMD 0.68UH 20% 17A(CMLE061H-R68MS-01'      | 'CHIP'         | ''          | ''   | '20220818'  
 '0.68UH/17A'                   | 'SMLF'     | 'EMPTY'  | 'CV+68H0MZ03'(!)           = ''              | ''                 | 'CV+68H0MZ03'              |'L_PCMS063T_6-6X6-6_H79'| 'NA'                           | 'IO'       | 'IND SMD 0.68UH 20% 17A(CMLE061H-R68MS-01'      | 'CHIP'         | ''          | ''   | '20220818'  
 '220NH/47A'                    | 'SMLF'     | 'IND'    | 'CV+22^0EZ06'(!)           = ''              | ''                 | 'CV+22^0EZ06'              |'L_HCME706713Q-221QL_7X6-7'| '220NH/47A'                    | 'DISCRETE' | 'IND SMD 220NH 15% 47A(HCME706713Q-221QL)'      | 'CHIP'         | ''          | ''   | '20220818'  
 '220NH/47A'                    | 'SMLF'     | 'EMPTY'  | 'CV+22^0EZ06'(!)           = ''              | ''                 | 'CV+22^0EZ06'              |'L_HCME706713Q-221QL_7X6-7'| 'NA'                           | 'IO'       | 'IND SMD 220NH 15% 47A(HCME706713Q-221QL)'      | 'CHIP'         | ''          | ''   | '20220818'  
 '4.7UH/1.15A'                  | 'SMLF'     | 'IND'    | 'CV-4712MZ03'(!)           = ''              | ''                 | 'CV-4712MZ03'              |'L_MSCDRI-4D18C_5-1X5-1'| '4.7UH/1.15A'                  | 'DISCRETE' | 'IND SMD 4.7UH,+-20%,1.15A(MSCDRI-4D18C)'       | 'CHIP'         | ''          | ''   | '20220825'  
 '4.7UH/1.15A'                  | 'SMLF'     | 'EMPTY'  | 'CV-4712MZ03'(!)           = ''              | ''                 | 'CV-4712MZ03'              |'L_MSCDRI-4D18C_5-1X5-1'| 'NA'                           | 'IO'       | 'IND SMD 4.7UH,+-20%,1.15A(MSCDRI-4D18C)'       | 'CHIP'         | ''          | ''   | '20220825'  
 '0.18UH/60A'                   | 'SMLF'     | 'IND'    | 'CV+18^0KZ17'(!)           = ''              | ''                 | 'CV+18^0KZ17'              |'L_AF13A-120K_9-6X6-4'| '0.18UH/60A'                   | 'DISCRETE' | 'IND SMD 0.18UH 10% 60A(MSI-900609V-R18K'       | 'CHIP'         | ''          | ''   | '20220912'  
 '0.18UH/60A'                   | 'SMLF'     | 'EMPTY'  | 'CV+18^0KZ17'(!)           = ''              | ''                 | 'CV+18^0KZ17'              |'L_AF13A-120K_9-6X6-4'| 'NA'                           | 'IO'       | 'IND SMD 0.18UH 10% 60A(MSI-900609V-R18K'       | 'CHIP'         | ''          | ''   | '20220912'  
 '0.4UH/40A'                    | 'SMLF'     | 'IND'    | 'CV+40^0KZ06'(!)           = ''              | ''                 | 'CV+40^0KZ06'              |'L_HCUVD8095D-102KBQL_8X8'| '0.4UH/40A'                    | 'DISCRETE' | 'IND SMD 0.4UH 10% 40A(MSI-800810V-R40K'        | 'CHIP'         | ''          | ''   | '20220912'  
 '0.4UH/40A'                    | 'SMLF'     | 'EMPTY'  | 'CV+40^0KZ06'(!)           = ''              | ''                 | 'CV+40^0KZ06'              |'L_HCUVD8095D-102KBQL_8X8'| 'NA'                           | 'IO'       | 'IND SMD 0.4UH 10% 40A(MSI-800810V-R40K'        | 'CHIP'         | ''          | ''   | '20220912'  
 '100NH/105A'                   | 'SMLF'     | 'IND'    | 'CV+10^0EZ09'(!)           = ''              | ''                 | 'CV+10^0EZ09'              |'L_HCME706713Q-221QL_7X6-7'| '100NH/105A'                   | 'DISCRETE' | 'IND SMD 100NH 15% 105A(PGL6827.101BHLT)'       | 'CHIP'         | ''          | ''   | '20220916'  
 '100NH/105A'                   | 'SMLF'     | 'EMPTY'  | 'CV+10^0EZ09'(!)           = ''              | ''                 | 'CV+10^0EZ09'              |'L_HCME706713Q-221QL_7X6-7'| 'NA'                           | 'IO'       | 'IND SMD 100NH 15% 105A(PGL6827.101BHLT)'       | 'CHIP'         | ''          | ''   | '20220916'  
 '150NH/70A'                    | 'SMLF'     | 'IND'    | 'CV+15^0EZ15'(!)           = ''              | ''                 | 'CV+15^0EZ15'              |'L_HCME706713Q-221QL_7X6-7'| '150NH/70A'                    | 'DISCRETE' | 'IND SMD 150NH 15% 70A(PGL6827.151BHLT)'        | 'CHIP'         | ''          | ''   | '20220916'  
 '150NH/70A'                    | 'SMLF'     | 'EMPTY'  | 'CV+15^0EZ15'(!)           = ''              | ''                 | 'CV+15^0EZ15'              |'L_HCME706713Q-221QL_7X6-7'| 'NA'                           | 'IO'       | 'IND SMD 150NH 15% 70A(PGL6827.151BHLT)'        | 'CHIP'         | ''          | ''   | '20220916'  
 '100NH/105A'                   | 'SMLF'     | 'IND'    | 'CV+10^0EZ10'(!)           = ''              | ''                 | 'CV+10^0EZ10'              |'L_HCME706713Q-221QL_7X6-7'| '100NH/105A'                   | 'DISCRETE' | 'IND SMD 100NH 15% 105A(HCME706713Q-101QL'      | 'CHIP'         | ''          | ''   | '20220920'  
 '100NH/105A'                   | 'SMLF'     | 'EMPTY'  | 'CV+10^0EZ10'(!)           = ''              | ''                 | 'CV+10^0EZ10'              |'L_HCME706713Q-221QL_7X6-7'| 'NA'                           | 'IO'       | 'IND SMD 100NH 15% 105A(HCME706713Q-101QL'      | 'CHIP'         | ''          | ''   | '20220920'  
 '150NH/70A'                    | 'SMLF'     | 'IND'    | 'CV+15^0EZ16'(!)           = ''              | ''                 | 'CV+15^0EZ16'              |'L_HCME706713Q-221QL_7X6-7'| '150NH/70A'                    | 'DISCRETE' | 'IND SMD 150NH 15% 70A(HCME706713Q-151QL'       | 'CHIP'         | ''          | ''   | '20220920'  
 '150NH/70A'                    | 'SMLF'     | 'EMPTY'  | 'CV+15^0EZ16'(!)           = ''              | ''                 | 'CV+15^0EZ16'              |'L_HCME706713Q-221QL_7X6-7'| 'NA'                           | 'IO'       | 'IND SMD 150NH 15% 70A(HCME706713Q-151QL'       | 'CHIP'         | ''          | ''   | '20220920'  
 'BLM21SN300SN1D/5A'            | 'SMLF'     | 'IND'    | 'CX300SN1000'(!)           = ''              | ''                 | 'CX300SN1000'              |'L0805'| 'BLM21SN300SN1D/5A'            | 'DISCRETE' | 'EMI FILTER BLM21SN300SN1D(30,8.5A)'            | 'CHIP'         | ''          | ''   | '20221019'  
 'BLM21SN300SN1D/5A'            | 'SMLF'     | 'EMPTY'  | 'CX300SN1000'(!)           = ''              | ''                 | 'CX300SN1000'              |'L0805'| 'NA'                           | 'IO'       | 'EMI FILTER BLM21SN300SN1D(30,8.5A)'            | 'CHIP'         | ''          | ''   | '20221019'  
 'BPH853025R5V-101T/30A'        | 'SMLF'     | 'IND'    | 'CXR5V101000'(!)           = ''              | ''                 | 'CXR5V101000'              |'L_BPH853025R5V-101T_8-5X3'| 'BPH853025R5V-101T/30A'        | 'DISCRETE' | 'EMI FILTER BEAD BPH853025R5(100,30A)AEC'       | 'CHIP'         | ''          | ''   | '20221020'  
 'BPH853025R5V-101T/30A'        | 'SMLF'     | 'EMPTY'  | 'CXR5V101000'(!)           = ''              | ''                 | 'CXR5V101000'              |'L_BPH853025R5V-101T_8-5X3'| 'NA'                           | 'IO'       | 'EMI FILTER BEAD BPH853025R5(100,30A)AEC'       | 'CHIP'         | ''          | ''   | '20221020'  
 '1UH/11A'                      | 'SMLF'     | 'IND'    | 'CV-10B0MZ53'(!)           = ''              | ''                 | 'CV-10B0MZ53'              |'L_CMLE053T_4-85X4-7'| '1UH/11A'                      | 'DISCRETE' | 'IND SMD 1UH 20% 11A(PIMB053T-1R0MT-39)'        | 'CHIP'         | ''          | ''   | '20221102'  
 '1UH/11A'                      | 'SMLF'     | 'EMPTY'  | 'CV-10B0MZ53'(!)           = ''              | ''                 | 'CV-10B0MZ53'              |'L_CMLE053T_4-85X4-7'| 'NA'                           | 'IO'       | 'IND SMD 1UH 20% 11A(PIMB053T-1R0MT-39)'        | 'CHIP'         | ''          | ''   | '20221102'  
 '120NH/87A'                    | 'SMLF'     | 'IND'    | 'CV+12^0EZ14'(!)           = ''              | ''                 | 'CV+12^0EZ14'              |'L_HCME706713Q-221QL_7X6-7'| '120NH/87A'                    | 'DISCRETE' | 'IND SMD 120NH 15% 87A(PGL6827.121BHLT)'        | 'CHIP'         | ''          | ''   | '20221102'  
 '120NH/87A'                    | 'SMLF'     | 'EMPTY'  | 'CV+12^0EZ14'(!)           = ''              | ''                 | 'CV+12^0EZ14'              |'L_HCME706713Q-221QL_7X6-7'| 'NA'                           | 'IO'       | 'IND SMD 120NH 15% 87A(PGL6827.121BHLT)'        | 'CHIP'         | ''          | ''   | '20221102'  
 '120NH/88A'                    | 'SMLF'     | 'IND'    | 'CV+12^0EZ15'(!)           = ''              | ''                 | 'CV+12^0EZ15'              |'L_HCME706713Q-221QL_7X6-7'| '120NH/88A'                    | 'DISCRETE' | 'IND SMD 120NH 15% 88A(HCME706713Q-121QL)'      | 'CHIP'         | ''          | ''   | '20221115'  
 '120NH/88A'                    | 'SMLF'     | 'EMPTY'  | 'CV+12^0EZ15'(!)           = ''              | ''                 | 'CV+12^0EZ15'              |'L_HCME706713Q-221QL_7X6-7'| 'NA'                           | 'IO'       | 'IND SMD 120NH 15% 88A(HCME706713Q-121QL)'      | 'CHIP'         | ''          | ''   | '20221115'  
 '220NH/44A'                    | 'SMLF'     | 'IND'    | 'CV+22^0KZ38'(!)           = ''              | ''                 | 'CV+22^0KZ38'              |'L_AF13A-120K_9-6X6-4'| '220NH/44A'                    | 'DISCRETE' | 'IND SMD 220NH 10% 44A(HCUVE966490Q-221QL'      | 'CHIP'         | ''          | ''   | '20221121'  
 '220NH/44A'                    | 'SMLF'     | 'EMPTY'  | 'CV+22^0KZ38'(!)           = ''              | ''                 | 'CV+22^0KZ38'              |'L_AF13A-120K_9-6X6-4'| 'NA'                           | 'IO'       | 'IND SMD 220NH 10% 44A(HCUVE966490Q-221QL'      | 'CHIP'         | ''          | ''   | '20221121'  
 '0.15UH/40A'                   | 'SMLF'     | 'IND'    | 'CV+15^0MZ10'(!)           = ''              | ''                 | 'CV+15^0MZ10'              |'L_PCMB104T-R15MS0R457_11-15X10'| '0.15UH/40A'                   | 'DISCRETE' | 'IND SMD 0.15UH20%40A PCMB104T-R15MS0R457'      | 'CHIP'         | ''          | ''   | '20221128'  
 '0.15UH/40A'                   | 'SMLF'     | 'EMPTY'  | 'CV+15^0MZ10'(!)           = ''              | ''                 | 'CV+15^0MZ10'              |'L_PCMB104T-R15MS0R457_11-15X10'| 'NA'                           | 'IO'       | 'IND SMD 0.15UH20%40A PCMB104T-R15MS0R457'      | 'CHIP'         | ''          | ''   | '20221128'  
 '220NH/61A'                    | 'SMLF'     | 'IND'    | 'CV+22^0KZ40'(!)           = ''              | ''                 | 'CV+22^0KZ40'              |'L_HCUVE966412D-221'| '220NH/61A'                    | 'DISCRETE' | 'IND SMD 220NH 10% 61A(HCUVE9612Q-221QL)'       | 'CHIP'         | ''          | ''   | '20221205'  
 '220NH/61A'                    | 'SMLF'     | 'EMPTY'  | 'CV+22^0KZ40'(!)           = ''              | ''                 | 'CV+22^0KZ40'              |'L_HCUVE966412D-221'| 'NA'                           | 'IO'       | 'IND SMD 220NH 10% 61A(HCUVE9612Q-221QL)'       | 'CHIP'         | ''          | ''   | '20221205'  
 '0.33UH/82A'                   | 'SMLF'     | 'IND'    | 'CV+33^0MZ04'(!)           = ''              | ''                 | 'CV+33^0MZ04'              |'L_CMMS136E_13-45X12-6'| '0.33UH/82A'                   | 'DISCRETE' | 'IND SMD 0.33UH 20% 82A(CMMS136E-R33MSQ)'       | 'CHIP'         | ''          | ''   | '20221205'  
 '0.33UH/82A'                   | 'SMLF'     | 'EMPTY'  | 'CV+33^0MZ04'(!)           = ''              | ''                 | 'CV+33^0MZ04'              |'L_CMMS136E_13-45X12-6'| 'NA'                           | 'IO'       | 'IND SMD 0.33UH 20% 82A(CMMS136E-R33MSQ)'       | 'CHIP'         | ''          | ''   | '20221205'  
 'FB MJ1608HS220NTR/7.5A'       | 'SMLF'     | 'IND'    | 'CX000220000'(!)           = ''              | ''                 | 'CX000220000'              |'L0603_H40'| 'FB MJ1608HS220NTR/7.5A'       | 'DISCRETE' | 'EMI FILTER BEAD FBMJ1608HS220NTR(22,7.5A'      | 'CHIP'         | ''          | ''   | '20221205'  
 'FB MJ1608HS220NTR/7.5A'       | 'SMLF'     | 'EMPTY'  | 'CX000220000'(!)           = ''              | ''                 | 'CX000220000'              |'L0603_H40'| 'NA'                           | 'IO'       | 'EMI FILTER BEAD FBMJ1608HS220NTR(22,7.5A'      | 'CHIP'         | ''          | ''   | '20221205'  
 '10UH/4A'                      | 'SMLF'     | 'IND'    | 'CV01040MZ09'(!)           = ''              | ''                 | 'CV01040MZ09'              |'L_EM-100M05V05_7-2X6-6'| '10UH/4A'                      | 'DISCRETE' | 'IND SMD 10UH +-20% 4A(EM-100M05V05)'           | 'CHIP'         | ''          | ''   | '20221205'  
 '10UH/4A'                      | 'SMLF'     | 'EMPTY'  | 'CV01040MZ09'(!)           = ''              | ''                 | 'CV01040MZ09'              |'L_EM-100M05V05_7-2X6-6'| 'NA'                           | 'IO'       | 'IND SMD 10UH +-20% 4A(EM-100M05V05)'           | 'CHIP'         | ''          | ''   | '20221205'  
 '1UH/50A'                      | 'SMLF'     | 'IND'    | 'CV-10^0MZ24'(!)           = ''              | ''                 | 'CV-10^0MZ24'              |'L_ZPWM-1250M_13-5X12-8'| '1UH/50A'                      | 'DISCRETE' | 'IND SMD 1UH 20% 50A(ZPWM-1250M-1R0M)'          | 'CHIP'         | ''          | ''   | '20221205'  
 '1UH/50A'                      | 'SMLF'     | 'EMPTY'  | 'CV-10^0MZ24'(!)           = ''              | ''                 | 'CV-10^0MZ24'              |'L_ZPWM-1250M_13-5X12-8'| 'NA'                           | 'IO'       | 'IND SMD 1UH 20% 50A(ZPWM-1250M-1R0M)'          | 'CHIP'         | ''          | ''   | '20221205'  
 '0.33UH/65A'                   | 'SMLF'     | 'IND'    | 'CV+33^0MZ09'(!)           = ''              | ''                 | 'CV+33^0MZ09'              |'L_ZPWM-1250M_13-5X12-8_H256'| '0.33UH/65A'                   | 'DISCRETE' | 'IND SMD 0.33UH 20% 65A(ZPWM-1265M-R33M)'       | 'CHIP'         | ''          | ''   | '20221205'  
 '0.33UH/65A'                   | 'SMLF'     | 'EMPTY'  | 'CV+33^0MZ09'(!)           = ''              | ''                 | 'CV+33^0MZ09'              |'L_ZPWM-1250M_13-5X12-8_H256'| 'NA'                           | 'IO'       | 'IND SMD 0.33UH 20% 65A(ZPWM-1265M-R33M)'       | 'CHIP'         | ''          | ''   | '20221205'  
 '2.2UH/17A'                    | 'SMLF'     | 'IND'    | 'CV-22H0MZ04'(!)           = ''              | ''                 | 'CV-22H0MZ04'              |'L_VCMT063T-2R2MN5'| '2.2UH/17A'                    | 'DISCRETE' | 'IND SMD 2.2UH 20% 17A(ZPWM-6030DA-2R2M)'       | 'CHIP'         | ''          | ''   | '20221205'  
 '2.2UH/17A'                    | 'SMLF'     | 'EMPTY'  | 'CV-22H0MZ04'(!)           = ''              | ''                 | 'CV-22H0MZ04'              |'L_VCMT063T-2R2MN5'| 'NA'                           | 'IO'       | 'IND SMD 2.2UH 20% 17A(ZPWM-6030DA-2R2M)'       | 'CHIP'         | ''          | ''   | '20221205'  
 '220NH/65A'                    | 'SMLF'     | 'IND'    | 'CV+22^0KZ49'(!)           = ''              | ''                 | 'CV+22^0KZ49'              |'L_ZPWE-906012MA_9-6X6-6'| '220NH/65A'                    | 'DISCRETE' | 'IND SMD 220NH 10% 65A(ZPWE-906012MA-R22K'      | 'CHIP'         | ''          | ''   | '20221205'  
 '220NH/65A'                    | 'SMLF'     | 'EMPTY'  | 'CV+22^0KZ49'(!)           = ''              | ''                 | 'CV+22^0KZ49'              |'L_ZPWE-906012MA_9-6X6-6'| 'NA'                           | 'IO'       | 'IND SMD 220NH 10% 65A(ZPWE-906012MA-R22K'      | 'CHIP'         | ''          | ''   | '20221205'  
 'MHC2012S601NBP/2000MA'        | 'SMLF'     | 'IND'    | 'CX12S601004'(!)           = ''              | ''                 | 'CX12S601004'              |'L0805_H44'| 'MHC2012S601NBP/2000MA'        | 'DISCRETE' | 'EMI FILTER MHC2012S601NBP(600,2000MA)'         | 'CHIP'         | ''          | ''   | '20230109'  
 'MHC2012S601NBP/2000MA'        | 'SMLF'     | 'EMPTY'  | 'CX12S601004'(!)           = ''              | ''                 | 'CX12S601004'              |'L0805_H44'| 'NA'                           | 'IO'       | 'EMI FILTER MHC2012S601NBP(600,2000MA)'         | 'CHIP'         | ''          | ''   | '20230109'  
 'HCB2012VF-331T25/2500MA'      | 'SMLF'     | 'IND'    | 'CX331T25002'(!)           = ''              | ''                 | 'CX331T25002'              |'L0805'| 'HCB2012VF-331T25/2500MA'      | 'DISCRETE' | 'EMI FILTER HCB2012VF-331T25(330,2500MA)'       | 'CHIP'         | ''          | ''   | '20230112'  
 'HCB2012VF-331T25/2500MA'      | 'SMLF'     | 'EMPTY'  | 'CX331T25002'(!)           = ''              | ''                 | 'CX331T25002'              |'L0805'| 'NA'                           | 'IO'       | 'EMI FILTER HCB2012VF-331T25(330,2500MA)'       | 'CHIP'         | ''          | ''   | '20230112'  
 '2.2UH/13A'                    | 'SMLF'     | 'IND'    | 'CV-22D0MZ06'(!)           = ''              | ''                 | 'CV-22D0MZ06'              |'L_PCMB103T-2R2MS_10-1X10'| '2.2UH/13A'                    | 'DISCRETE' | 'IND SMD 2.2U 20%13A(PCMB103T-2R2MS)'           | 'CHIP'         | ''          | ''   | '20230111'  
 '2.2UH/13A'                    | 'SMLF'     | 'EMPTY'  | 'CV-22D0MZ06'(!)           = ''              | ''                 | 'CV-22D0MZ06'              |'L_PCMB103T-2R2MS_10-1X10'| 'NA'                           | 'IO'       | 'IND SMD 2.2U 20%13A(PCMB103T-2R2MS)'           | 'CHIP'         | ''          | ''   | '20230111'  
 '100NH/77A'                    | 'SMLF'     | 'IND'    | 'CV+10^0EZ04'(!)           = ''              | ''                 | 'CV+10^0EZ04'              |'L_HCME1012Q-121QL_10X6'| '100NH/77A'                    | 'DISCRETE' | 'IND SMD 100NH +-15% 77A(PA4990.101HLT)'        | 'CHIP'         | ''          | ''   | '20230130'  
 '100NH/77A'                    | 'SMLF'     | 'EMPTY'  | 'CV+10^0EZ04'(!)           = ''              | ''                 | 'CV+10^0EZ04'              |'L_HCME1012Q-121QL_10X6'| 'NA'                           | 'IO'       | 'IND SMD 100NH +-15% 77A(PA4990.101HLT)'        | 'CHIP'         | ''          | ''   | '20230130'  
 '400NH/21A'                    | 'SMLF'     | 'IND'    | 'CV+40L0KZ01'(!)           = ''              | ''                 | 'CV+40L0KZ01'              |'L_HCUVE966490D-121'| '400NH/21A'                    | 'DISCRETE' | 'IND SMD 400NH 10% 21A(HCUVE966490Q-401QL'      | 'CHIP'         | ''          | ''   | '20230130'  
 '400NH/21A'                    | 'SMLF'     | 'EMPTY'  | 'CV+40L0KZ01'(!)           = ''              | ''                 | 'CV+40L0KZ01'              |'L_HCUVE966490D-121'| 'NA'                           | 'IO'       | 'IND SMD 400NH 10% 21A(HCUVE966490Q-401QL'      | 'CHIP'         | ''          | ''   | '20230130'  
 '100NH/129A'                   | 'SMLF'     | 'IND'    | 'CV+10^0EZ00'(!)           = ''              | ''                 | 'CV+10^0EZ00'              |'L_L101247A-120L_10X6-4'| '100NH/129A'                   | 'DISCRETE' | 'IND SMD 100NH +-15% 129A L101247A-100L'        | 'CHIP'         | ''          | ''   | '20230130'  
 '100NH/129A'                   | 'SMLF'     | 'EMPTY'  | 'CV+10^0EZ00'(!)           = ''              | ''                 | 'CV+10^0EZ00'              |'L_L101247A-120L_10X6-4'| 'NA'                           | 'IO'       | 'IND SMD 100NH +-15% 129A L101247A-100L'        | 'CHIP'         | ''          | ''   | '20230130'  
 '0.68UH/34A'                   | 'SMLF'     | 'IND'    | 'CV+68Z0MZ03'(!)           = ''              | ''                 | 'CV+68Z0MZ03'              |'L_MMD-12EZ_13-7X12-9'| '0.68UH/34A'                   | 'DISCRETE' | 'IND SMD 0.68UH20%,34A(MMD-12EZ-R68M-V1Q)'      | 'CHIP'         | ''          | ''   | '20230208'  
 '0.68UH/34A'                   | 'SMLF'     | 'EMPTY'  | 'CV+68Z0MZ03'(!)           = ''              | ''                 | 'CV+68Z0MZ03'              |'L_MMD-12EZ_13-7X12-9'| 'NA'                           | 'IO'       | 'IND SMD 0.68UH20%,34A(MMD-12EZ-R68M-V1Q)'      | 'CHIP'         | ''          | ''   | '20230208'  
 'BLM15PG100SN1D/1000MA'        | 'SMLF'     | 'IND'    | 'CX5PG100000'(!)           = ''              | ''                 | 'CX5PG100000'              |'L0402'| 'BLM15PG100SN1D/1000MA'        | 'DISCRETE' | 'EMI FILTER BLM15PG100SN1D(10,1000MA)'          | 'CHIP'         | ''          | ''   | '20230213'  
 'BLM15PG100SN1D/1000MA'        | 'SMLF'     | 'EMPTY'  | 'CX5PG100000'(!)           = ''              | ''                 | 'CX5PG100000'              |'L0402'| 'NA'                           | 'IO'       | 'EMI FILTER BLM15PG100SN1D(10,1000MA)'          | 'CHIP'         | ''          | ''   | '20230213'  
 'BPPB-F854625121X0E/10A'       | 'SMLF'     | 'IND'    | 'CX546251000'(!)           = ''              | ''                 | 'CX546251000'              |'L_BPPB-F854625121X0E_8-51X4-6'| 'BPPB-F854625121X0E/10A'       | 'DISCRETE' | 'EMI FILTER BPPB-F854625121X0E(115,10A)'        | 'CHIP'         | ''          | ''   | '20230523'  
 'BPPB-F854625121X0E/10A'       | 'SMLF'     | 'EMPTY'  | 'CX546251000'(!)           = ''              | ''                 | 'CX546251000'              |'L_BPPB-F854625121X0E_8-51X4-6'| 'NA'                           | 'IO'       | 'EMI FILTER BPPB-F854625121X0E(115,10A)'        | 'CHIP'         | ''          | ''   | '20230523'  
 '70NH/170A'                    | 'SMLF'     | 'IND'    | 'CVA70^0EZ05'(!)           = ''              | ''                 | 'CVA70^0EZ05'              |'L_HCME117513Q-700QL_11X7-5'| '70NH/170A'                    | 'DISCRETE' | 'IND SMD 70NH 15% 170A(HCME117513Q-700QL)'      | 'CHIP'         | ''          | ''   | '20230531'  
 '70NH/170A'                    | 'SMLF'     | 'EMPTY'  | 'CVA70^0EZ05'(!)           = ''              | ''                 | 'CVA70^0EZ05'              |'L_HCME117513Q-700QL_11X7-5'| 'NA'                           | 'IO'       | 'IND SMD 70NH 15% 170A(HCME117513Q-700QL)'      | 'CHIP'         | ''          | ''   | '20230531'  
 'GMLB-201209-0600Y-GK-QU/0.5A' | 'SMLF'     | 'IND'    | 'CX090600003'(!)           = ''              | ''                 | 'CX090600003'              |'L0805_H44'| 'GMLB-201209-0600Y-GK-QU/0.5A' | 'DISCRETE' | 'EMI FILTER GMLB-201209-0600Y(600,0.5A)'        | 'CHIP'         | ''          | ''   | '20230531'  
 'GMLB-201209-0600Y-GK-QU/0.5A' | 'SMLF'     | 'EMPTY'  | 'CX090600003'(!)           = ''              | ''                 | 'CX090600003'              |'L0805_H44'| 'NA'                           | 'IO'       | 'EMI FILTER GMLB-201209-0600Y(600,0.5A)'        | 'CHIP'         | ''          | ''   | '20230531'  
 '4.7UH/6.5A'                   | 'SMLF'     | 'IND'    | 'CV-4765MZ19'(!)           = ''              | ''                 | 'CV-4765MZ19'              |'L_MSCDRI-105A_10-2X10'| '4.7UH/6.5A'                   | 'DISCRETE' | 'IND SMD 4.7UH 20% 6.5A(MSCDRI-105A-4R7M)'      | 'CHIP'         | ''          | ''   | '20230609'  
 '4.7UH/6.5A'                   | 'SMLF'     | 'EMPTY'  | 'CV-4765MZ19'(!)           = ''              | ''                 | 'CV-4765MZ19'              |'L_MSCDRI-105A_10-2X10'| 'NA'                           | 'IO'       | 'IND SMD 4.7UH 20% 6.5A(MSCDRI-105A-4R7M)'      | 'CHIP'         | ''          | ''   | '20230609'  
 '4.7UH/16A'                    | 'SMLF'     | 'IND'    | 'CV-47G0MZ01'(!)           = ''              | ''                 | 'CV-47G0MZ01'              |'L_TMPA1005S_10X10'| '4.7UH/16A'                    | 'DISCRETE' | 'IND SMD 4.7UH 20% 16A(TMPA1005S-4R7MN-D)'      | 'CHIP'         | ''          | ''   | '20230621'  
 '4.7UH/16A'                    | 'SMLF'     | 'EMPTY'  | 'CV-47G0MZ01'(!)           = ''              | ''                 | 'CV-47G0MZ01'              |'L_TMPA1005S_10X10'| 'NA'                           | 'IO'       | 'IND SMD 4.7UH 20% 16A(TMPA1005S-4R7MN-D)'      | 'CHIP'         | ''          | ''   | '20230621'  
 '0.1UH/35A'                    | 'SMLF'     | 'IND'    | 'CV+10^0MZ05SEL1'(!)       = ''              | ''                 | 'CV+10^0MZ05SEL1'          |'L_MSI-600608'| '0.1UH/35A'                    | 'DISCRETE' | 'IND SMD 0.1UH +-20% 35A MSI-6006 SELASN'       | 'CHIP'         | ''          | ''   | '20230626'  
 '0.1UH/35A'                    | 'SMLF'     | 'EMPTY'  | 'CV+10^0MZ05SEL1'(!)       = ''              | ''                 | 'CV+10^0MZ05SEL1'          |'L_MSI-600608'| 'NA'                           | 'IO'       | 'IND SMD 0.1UH +-20% 35A MSI-6006 SELASN'       | 'CHIP'         | ''          | ''   | '20230626'  
 '100NH/16A'                    | 'SMLF'     | 'IND'    | 'CV+10G0MZ04SEL1'(!)       = ''              | ''                 | 'CV+10G0MZ04SEL1'          |'L_HCBS4545_4-5X4-5'| '100NH/16A'                    | 'DISCRETE' | 'IND SMD 100NH 20% 16A(HCBS4545 SELASN'         | 'CHIP'         | ''          | ''   | '20230626'  
 '100NH/16A'                    | 'SMLF'     | 'EMPTY'  | 'CV+10G0MZ04SEL1'(!)       = ''              | ''                 | 'CV+10G0MZ04SEL1'          |'L_HCBS4545_4-5X4-5'| 'NA'                           | 'IO'       | 'IND SMD 100NH 20% 16A(HCBS4545 SELASN'         | 'CHIP'         | ''          | ''   | '20230626'  
 '120NH/69A'                    | 'SMLF'     | 'IND'    | 'CV+12^0EZ04SEL1'(!)       = ''              | ''                 | 'CV+12^0EZ04SEL1'          |'L_VLBU6565100T-R12L-1_6-5X6-5'| '120NH/69A'                    | 'DISCRETE' | 'IND SMD 120NH 15% 69A(HCME656510 SELASN'       | 'CHIP'         | ''          | ''   | '20230626'  
 '120NH/69A'                    | 'SMLF'     | 'EMPTY'  | 'CV+12^0EZ04SEL1'(!)       = ''              | ''                 | 'CV+12^0EZ04SEL1'          |'L_VLBU6565100T-R12L-1_6-5X6-5'| 'NA'                           | 'IO'       | 'IND SMD 120NH 15% 69A(HCME656510 SELASN'       | 'CHIP'         | ''          | ''   | '20230626'  
 '0.12UH/69A'                   | 'SMLF'     | 'IND'    | 'CV+12^0EZ07SEL1'(!)       = ''              | ''                 | 'CV+12^0EZ07SEL1'          |'L_VLBU6565100T-R12L-1_6-5X6-5'| '0.12UH/69A'                   | 'DISCRETE' | 'IND SMD 0.12UH 15% 69A(VLBU6565 SELASN'        | 'CHIP'         | ''          | ''   | '20230626'  
 '0.12UH/69A'                   | 'SMLF'     | 'EMPTY'  | 'CV+12^0EZ07SEL1'(!)       = ''              | ''                 | 'CV+12^0EZ07SEL1'          |'L_VLBU6565100T-R12L-1_6-5X6-5'| 'NA'                           | 'IO'       | 'IND SMD 0.12UH 15% 69A(VLBU6565 SELASN'        | 'CHIP'         | ''          | ''   | '20230626'  
 '130NH/106A'                   | 'SMLF'     | 'IND'    | 'CV+13^0KZ01SEL1'(!)       = ''              | ''                 | 'CV+13^0KZ01SEL1'          |'L_HCME107512-131_10X7-5'| '130NH/106A'                   | 'DISCRETE' | 'IND SMD 130NH 10% 106A(HCME10751 SELASN'       | 'CHIP'         | ''          | ''   | '20230626'  
 '130NH/106A'                   | 'SMLF'     | 'EMPTY'  | 'CV+13^0KZ01SEL1'(!)       = ''              | ''                 | 'CV+13^0KZ01SEL1'          |'L_HCME107512-131_10X7-5'| 'NA'                           | 'IO'       | 'IND SMD 130NH 10% 106A(HCME10751 SELASN'       | 'CHIP'         | ''          | ''   | '20230626'  
 '130NH/95A'                    | 'SMLF'     | 'IND'    | 'CV+13^0KZ09SEL1'(!)       = ''              | ''                 | 'CV+13^0KZ09SEL1'          |'L_HCUVE768012-171_7-6X8-1'| '130NH/95A'                    | 'DISCRETE' | 'IND SMD 130NH 10% 95A(HCUVE76801 SELASN'       | 'CHIP'         | ''          | ''   | '20230626'  
 '130NH/95A'                    | 'SMLF'     | 'EMPTY'  | 'CV+13^0KZ09SEL1'(!)       = ''              | ''                 | 'CV+13^0KZ09SEL1'          |'L_HCUVE768012-171_7-6X8-1'| 'NA'                           | 'IO'       | 'IND SMD 130NH 10% 95A(HCUVE76801 SELASN'       | 'CHIP'         | ''          | ''   | '20230626'  
 '130NH/106A'                   | 'SMLF'     | 'IND'    | 'CV+13^0KZ11SEL1'(!)       = ''              | ''                 | 'CV+13^0KZ11SEL1'          |'L_HCME107512-131_10X7-5'| '130NH/106A'                   | 'DISCRETE' | 'IND SMD 130NH 10% 106A(PG2323.1 SELASN'        | 'CHIP'         | ''          | ''   | '20230626'  
 '130NH/106A'                   | 'SMLF'     | 'EMPTY'  | 'CV+13^0KZ11SEL1'(!)       = ''              | ''                 | 'CV+13^0KZ11SEL1'          |'L_HCME107512-131_10X7-5'| 'NA'                           | 'IO'       | 'IND SMD 130NH 10% 106A(PG2323.1 SELASN'        | 'CHIP'         | ''          | ''   | '20230626'  
 '220NH/81A'                    | 'SMLF'     | 'IND'    | 'CV+22^0KZ10SEL1'(!)       = ''              | ''                 | 'CV+22^0KZ10SEL1'          |'L_HCUV117512_10-7X7-5'| '220NH/81A'                    | 'DISCRETE' | 'IND SMD 220NH 10% 81A(HCUV117512 SELASN'       | 'CHIP'         | ''          | ''   | '20230626'  
 '220NH/81A'                    | 'SMLF'     | 'EMPTY'  | 'CV+22^0KZ10SEL1'(!)       = ''              | ''                 | 'CV+22^0KZ10SEL1'          |'L_HCUV117512_10-7X7-5'| 'NA'                           | 'IO'       | 'IND SMD 220NH 10% 81A(HCUV117512 SELASN'       | 'CHIP'         | ''          | ''   | '20230626'  
 '0.33UH/40A'                   | 'SMLF'     | 'IND'    | 'CV+33^0TZ00SEL1'(!)       = ''              | ''                 | 'CV+33^0TZ00SEL1'          |'L_HCME1012Q-121QL_10X6'| '0.33UH/40A'                   | 'DISCRETE' | 'IND SMD 0.33UH 15% 40A(PA4990.331 SELASN'      | 'CHIP'         | ''          | ''   | '20230626'  
 '0.33UH/40A'                   | 'SMLF'     | 'EMPTY'  | 'CV+33^0TZ00SEL1'(!)       = ''              | ''                 | 'CV+33^0TZ00SEL1'          |'L_HCME1012Q-121QL_10X6'| 'NA'                           | 'IO'       | 'IND SMD 0.33UH 15% 40A(PA4990.331 SELASN'      | 'CHIP'         | ''          | ''   | '20230626'  
 '0.33UH/20A'                   | 'SMLF'     | 'IND'    | 'CV+33K0MZ03SEL1'(!)       = ''              | ''                 | 'CV+33K0MZ03SEL1'          |'L_PCMC063T'| '0.33UH/20A'                   | 'DISCRETE' | 'IND 0.33UH(20A +-20%,PCMC063T SELASN'          | 'CHIP'         | ''          | ''   | '20230626'  
 '0.33UH/20A'                   | 'SMLF'     | 'EMPTY'  | 'CV+33K0MZ03SEL1'(!)       = ''              | ''                 | 'CV+33K0MZ03SEL1'          |'L_PCMC063T'| 'NA'                           | 'IO'       | 'IND 0.33UH(20A +-20%,PCMC063T SELASN'          | 'CHIP'         | ''          | ''   | '20230626'  
 '330NH/26A'                    | 'SMLF'     | 'IND'    | 'CV+33R0EZ00SEL1'(!)       = ''              | ''                 | 'CV+33R0EZ00SEL1'          |'L_HCME0711Q-121LQL_7X6-7'| '330NH/26A'                    | 'DISCRETE' | 'IND SMD 330NH 15% 26A(HCME0711Q SELASN'        | 'CHIP'         | ''          | ''   | '20230626'  
 '330NH/26A'                    | 'SMLF'     | 'EMPTY'  | 'CV+33R0EZ00SEL1'(!)       = ''              | ''                 | 'CV+33R0EZ00SEL1'          |'L_HCME0711Q-121LQL_7X6-7'| 'NA'                           | 'IO'       | 'IND SMD 330NH 15% 26A(HCME0711Q SELASN'        | 'CHIP'         | ''          | ''   | '20230626'  
 '0.47UH/63A'                   | 'SMLF'     | 'IND'    | 'CV+47^0MZ08SEL1'(!)       = ''              | ''                 | 'CV+47^0MZ08SEL1'          |'L_MMD12FD'| '0.47UH/63A'                   | 'DISCRETE' | 'IND SMD 0.47UH 20% 63A MMD-12FD SELASN'        | 'CHIP'         | ''          | ''   | '20230626'  
 '0.47UH/63A'                   | 'SMLF'     | 'EMPTY'  | 'CV+47^0MZ08SEL1'(!)       = ''              | ''                 | 'CV+47^0MZ08SEL1'          |'L_MMD12FD'| 'NA'                           | 'IO'       | 'IND SMD 0.47UH 20% 63A MMD-12FD SELASN'        | 'CHIP'         | ''          | ''   | '20230626'  
 '0.47UH/12A'                   | 'SMLF'     | 'IND'    | 'CV+47C0MZ00SEL1'(!)       = ''              | ''                 | 'CV+47C0MZ00SEL1'          |'L_CMME053T_4-5X4-7'| '0.47UH/12A'                   | 'DISCRETE' | 'IND SMD 0.47UH 20% 12A(PCMB053T SELASN'        | 'CHIP'         | ''          | ''   | '20230626'  
 '0.47UH/12A'                   | 'SMLF'     | 'EMPTY'  | 'CV+47C0MZ00SEL1'(!)       = ''              | ''                 | 'CV+47C0MZ00SEL1'          |'L_CMME053T_4-5X4-7'| 'NA'                           | 'IO'       | 'IND SMD 0.47UH 20% 12A(PCMB053T SELASN'        | 'CHIP'         | ''          | ''   | '20230626'  
 '0.47UH/26A'                   | 'SMLF'     | 'IND'    | 'CV+47R0MZ07SEL1'(!)       = ''              | ''                 | 'CV+47R0MZ07SEL1'          |'L_PCMC063T'| '0.47UH/26A'                   | 'DISCRETE' | 'IND SMD 0.47UH 20% 26A(PCMC063T SELASN'        | 'CHIP'         | ''          | ''   | '20230626'  
 '0.47UH/26A'                   | 'SMLF'     | 'EMPTY'  | 'CV+47R0MZ07SEL1'(!)       = ''              | ''                 | 'CV+47R0MZ07SEL1'          |'L_PCMC063T'| 'NA'                           | 'IO'       | 'IND SMD 0.47UH 20% 26A(PCMC063T SELASN'        | 'CHIP'         | ''          | ''   | '20230626'  
 '0.68UH/34A'                   | 'SMLF'     | 'IND'    | 'CV+68Z0MZ04SEL1'(!)       = ''              | ''                 | 'CV+68Z0MZ04SEL1'          |'L_CMME104T_10-1X10'| '0.68UH/34A'                   | 'DISCRETE' | 'IND SMD 0.68UH20% 34A(CMME104T SELASN'         | 'CHIP'         | ''          | ''   | '20230626'  
 '0.68UH/34A'                   | 'SMLF'     | 'EMPTY'  | 'CV+68Z0MZ04SEL1'(!)       = ''              | ''                 | 'CV+68Z0MZ04SEL1'          |'L_CMME104T_10-1X10'| 'NA'                           | 'IO'       | 'IND SMD 0.68UH20% 34A(CMME104T SELASN'         | 'CHIP'         | ''          | ''   | '20230626'  
 '47UH/75MA'                    | 'SMLF'     | 'IND'    | 'CV04701KN03SEL1'(!)       = ''              | ''                 | 'CV04701KN03SEL1'          |'L0805_H62'| '47UH/75MA'                    | 'DISCRETE' | 'IND CHIP 47UH 10% 75MA(LBR2012T47 SELASN'      | 'CHIP'         | ''          | ''   | '20230626'  
 '47UH/75MA'                    | 'SMLF'     | 'EMPTY'  | 'CV04701KN03SEL1'(!)       = ''              | ''                 | 'CV04701KN03SEL1'          |'L0805_H62'| 'NA'                           | 'IO'       | 'IND CHIP 47UH 10% 75MA(LBR2012T47 SELASN'      | 'CHIP'         | ''          | ''   | '20230626'  
 '1.0UH/8.5A'                   | 'SMLF'     | 'IND'    | 'CV-1085MZ05SEL1'(!)       = ''              | ''                 | 'CV-1085MZ05SEL1'          |'L_HCM0503_5-15X5-1'| '1.0UH/8.5A'                   | 'DISCRETE' | 'IND SMD 1U 20%8.5A(HCM0503-1R0-R)SELASN'       | 'CHIP'         | ''          | ''   | '20230626'  
 '1.0UH/8.5A'                   | 'SMLF'     | 'EMPTY'  | 'CV-1085MZ05SEL1'(!)       = ''              | ''                 | 'CV-1085MZ05SEL1'          |'L_HCM0503_5-15X5-1'| 'NA'                           | 'IO'       | 'IND SMD 1U 20%8.5A(HCM0503-1R0-R)SELASN'       | 'CHIP'         | ''          | ''   | '20230626'  
 '1.0UH/18A'                    | 'SMLF'     | 'IND'    | 'CV-10I0MZ01SEL1'(!)       = ''              | ''                 | 'CV-10I0MZ01SEL1'          |'L_PCMC104T'| '1.0UH/18A'                    | 'DISCRETE' | 'IND SMD 1.0UH20% 18A(PCMC104T-1R0MN)SELA'      | 'CHIP'         | ''          | ''   | '20230626'  
 '1.0UH/18A'                    | 'SMLF'     | 'EMPTY'  | 'CV-10I0MZ01SEL1'(!)       = ''              | ''                 | 'CV-10I0MZ01SEL1'          |'L_PCMC104T'| 'NA'                           | 'IO'       | 'IND SMD 1.0UH20% 18A(PCMC104T-1R0MN)SELA'      | 'CHIP'         | ''          | ''   | '20230626'  
 '1.5UH/6A'                     | 'SMLF'     | 'IND'    | 'CV-1560MZ01SEL1'(!)       = ''              | ''                 | 'CV-1560MZ01SEL1'          |'L_CMME053T_4-5X4-7'| '1.5UH/6A'                     | 'DISCRETE' | 'IND SMD 1.5UH +-20% 6A(PCMB053T SELASN'        | 'CHIP'         | ''          | ''   | '20230626'  
 '1.5UH/6A'                     | 'SMLF'     | 'EMPTY'  | 'CV-1560MZ01SEL1'(!)       = ''              | ''                 | 'CV-1560MZ01SEL1'          |'L_CMME053T_4-5X4-7'| 'NA'                           | 'IO'       | 'IND SMD 1.5UH +-20% 6A(PCMB053T SELASN'        | 'CHIP'         | ''          | ''   | '20230626'  
 '2.2UH/5.5A'                   | 'SMLF'     | 'IND'    | 'CV-2255MZ02SEL1'(!)       = ''              | ''                 | 'CV-2255MZ02SEL1'          |'L_CMME053T_4-5X4-7'| '2.2UH/5.5A'                   | 'DISCRETE' | 'IND SMD 2.2UH +-20% 5.5A(PCMB SELASN'          | 'CHIP'         | ''          | ''   | '20230626'  
 '2.2UH/5.5A'                   | 'SMLF'     | 'EMPTY'  | 'CV-2255MZ02SEL1'(!)       = ''              | ''                 | 'CV-2255MZ02SEL1'          |'L_CMME053T_4-5X4-7'| 'NA'                           | 'IO'       | 'IND SMD 2.2UH +-20% 5.5A(PCMB SELASN'          | 'CHIP'         | ''          | ''   | '20230626'  
 '3.3UH/5A'                     | 'SMLF'     | 'IND'    | 'CV-3350MZ11SEL1'(!)       = ''              | ''                 | 'CV-3350MZ11SEL1'          |'L_CMME053T_4-5X4-7'| '3.3UH/5A'                     | 'DISCRETE' | 'IND SMD 3.3U 20% 5A(PCMB053T SELASN'           | 'CHIP'         | ''          | ''   | '20230626'  
 '3.3UH/5A'                     | 'SMLF'     | 'EMPTY'  | 'CV-3350MZ11SEL1'(!)       = ''              | ''                 | 'CV-3350MZ11SEL1'          |'L_CMME053T_4-5X4-7'| 'NA'                           | 'IO'       | 'IND SMD 3.3U 20% 5A(PCMB053T SELASN'           | 'CHIP'         | ''          | ''   | '20230626'  
 '4.7UH/4A'                     | 'SMLF'     | 'IND'    | 'CV-4740MZ03SEL1'(!)       = ''              | ''                 | 'CV-4740MZ03SEL1'          |'L_CMME053T_4-5X4-7'| '4.7UH/4A'                     | 'DISCRETE' | 'IND SMD 4.7UH +-20% 4A(PCMB053T SELASN'        | 'CHIP'         | ''          | ''   | '20230626'  
 '4.7UH/4A'                     | 'SMLF'     | 'EMPTY'  | 'CV-4740MZ03SEL1'(!)       = ''              | ''                 | 'CV-4740MZ03SEL1'          |'L_CMME053T_4-5X4-7'| 'NA'                           | 'IO'       | 'IND SMD 4.7UH +-20% 4A(PCMB053T SELASN'        | 'CHIP'         | ''          | ''   | '20230626'  
 '4.7UH/5.5A'                   | 'SMLF'     | 'IND'    | 'CV-4755MZ12SEL1'(!)       = ''              | ''                 | 'CV-4755MZ12SEL1'          |'L_PCMC063T'| '4.7UH/5.5A'                   | 'DISCRETE' | 'IND SMD 4.7U20%5.5A(PCMC063T-4R7 SELASN'       | 'CHIP'         | ''          | ''   | '20230626'  
 '4.7UH/5.5A'                   | 'SMLF'     | 'EMPTY'  | 'CV-4755MZ12SEL1'(!)       = ''              | ''                 | 'CV-4755MZ12SEL1'          |'L_PCMC063T'| 'NA'                           | 'IO'       | 'IND SMD 4.7U20%5.5A(PCMC063T-4R7 SELASN'       | 'CHIP'         | ''          | ''   | '20230626'  
 '6.8UH/4.5A'                   | 'SMLF'     | 'IND'    | 'CV-6845MZ05SEL1'(!)       = ''              | ''                 | 'CV-6845MZ05SEL1'          |'L_PCMC063T'| '6.8UH/4.5A'                   | 'DISCRETE' | 'IND SMD 6.8UH 20%,4.5A(PCMC063T SELASN'        | 'CHIP'         | ''          | ''   | '20230626'  
 '6.8UH/4.5A'                   | 'SMLF'     | 'EMPTY'  | 'CV-6845MZ05SEL1'(!)       = ''              | ''                 | 'CV-6845MZ05SEL1'          |'L_PCMC063T'| 'NA'                           | 'IO'       | 'IND SMD 6.8UH 20%,4.5A(PCMC063T SELASN'        | 'CHIP'         | ''          | ''   | '20230626'  
 '50NH/148A'                    | 'SMLF'     | 'IND'    | 'CVA50^0TZ00SEL1'(!)       = ''              | ''                 | 'CVA50^0TZ00SEL1'          |'L_HCBS1080-500QL_10X8-3'| '50NH/148A'                    | 'DISCRETE' | 'IND SMD 50NH 15% 148A(HCBS1080 SELASN'         | 'CHIP'         | ''          | ''   | '20230626'  
 '50NH/148A'                    | 'SMLF'     | 'EMPTY'  | 'CVA50^0TZ00SEL1'(!)       = ''              | ''                 | 'CVA50^0TZ00SEL1'          |'L_HCBS1080-500QL_10X8-3'| 'NA'                           | 'IO'       | 'IND SMD 50NH 15% 148A(HCBS1080 SELASN'         | 'CHIP'         | ''          | ''   | '20230626'  
 '90NH/137A'                    | 'SMLF'     | 'IND'    | 'CVA90^0KZ05SEL1'(!)       = ''              | ''                 | 'CVA90^0KZ05SEL1'          |'L_HCUVE768012Q-900QL_7-6X8-3'| '90NH/137A'                    | 'DISCRETE' | 'IND SMD 90NH 10% 137A(HCUVE768 SELASN'         | 'CHIP'         | ''          | ''   | '20230626'  
 '90NH/137A'                    | 'SMLF'     | 'EMPTY'  | 'CVA90^0KZ05SEL1'(!)       = ''              | ''                 | 'CVA90^0KZ05SEL1'          |'L_HCUVE768012Q-900QL_7-6X8-3'| 'NA'                           | 'IO'       | 'IND SMD 90NH 10% 137A(HCUVE768 SELASN'         | 'CHIP'         | ''          | ''   | '20230626'  
 'MLB-201209-0330P-N2/1.5A'     | 'SMLF'     | 'IND'    | 'CX00330P000SEL1'(!)       = ''              | ''                 | 'CX00330P000SEL1'          |'L0805'| 'MLB-201209-0330P-N2/1.5A'     | 'DISCRETE' | 'FILTER MLB-201209-0330P(330,1.5A) SELASN'      | 'CHIP'         | ''          | ''   | '20230626'  
 'MLB-201209-0330P-N2/1.5A'     | 'SMLF'     | 'EMPTY'  | 'CX00330P000SEL1'(!)       = ''              | ''                 | 'CX00330P000SEL1'          |'L0805'| 'NA'                           | 'IO'       | 'FILTER MLB-201209-0330P(330,1.5A) SELASN'      | 'CHIP'         | ''          | ''   | '20230626'  
 'GMLB-201209-0600Y-PY-QU/2A'   | 'SMLF'     | 'IND'    | 'CX090600002SEL1'(!)       = ''              | ''                 | 'CX090600002SEL1'          |'L0805_H44'| 'GMLB-201209-0600Y-PY-QU/2A'   | 'DISCRETE' | 'EMI FIL GMLB-201209-0600Y(600,2A) SELASN'      | 'CHIP'         | ''          | ''   | '20230626'  
 'GMLB-201209-0600Y-PY-QU/2A'   | 'SMLF'     | 'EMPTY'  | 'CX090600002SEL1'(!)       = ''              | ''                 | 'CX090600002SEL1'          |'L0805_H44'| 'NA'                           | 'IO'       | 'EMI FIL GMLB-201209-0600Y(600,2A) SELASN'      | 'CHIP'         | ''          | ''   | '20230626'  
 'MPZ2012S300ATD25/6A'          | 'SMLF'     | 'IND'    | 'CX12S300000SEL1'(!)       = ''              | ''                 | 'CX12S300000SEL1'          |'L0805'| 'MPZ2012S300ATD25/6A'          | 'DISCRETE' | 'EMI FIL MPZ2012S300ATD25(30,6A)SELA'           | 'CHIP'         | ''          | ''   | '20230626'  
 'MPZ2012S300ATD25/6A'          | 'SMLF'     | 'EMPTY'  | 'CX12S300000SEL1'(!)       = ''              | ''                 | 'CX12S300000SEL1'          |'L0805'| 'NA'                           | 'IO'       | 'EMI FIL MPZ2012S300ATD25(30,6A)SELA'           | 'CHIP'         | ''          | ''   | '20230626'  
 'BLM21PG331SN1D/1.5A'          | 'SMLF'     | 'IND'    | 'CX1PG331001SEL1'(!)       = ''              | ''                 | 'CX1PG331001SEL1'          |'L0805'| 'BLM21PG331SN1D/1.5A'          | 'DISCRETE' | 'EMI FIL CHIP BLM21PG(330,1.5A) SELASN'         | 'CHIP'         | ''          | ''   | '20230626'  
 'BLM21PG331SN1D/1.5A'          | 'SMLF'     | 'EMPTY'  | 'CX1PG331001SEL1'(!)       = ''              | ''                 | 'CX1PG331001SEL1'          |'L0805'| 'NA'                           | 'IO'       | 'EMI FIL CHIP BLM21PG(330,1.5A) SELASN'         | 'CHIP'         | ''          | ''   | '20230626'  
 'BLM21PG600SN1D/3A'            | 'SMLF'     | 'IND'    | 'CX1PG600001SEL1'(!)       = ''              | ''                 | 'CX1PG600001SEL1'          |'L0805'| 'BLM21PG600SN1D/3A'            | 'DISCRETE' | 'EMI FILTERCHIP BLM21PG600SN1D(60,3A)SELA'      | 'CHIP'         | ''          | ''   | '20230626'  
 'BLM21PG600SN1D/3A'            | 'SMLF'     | 'EMPTY'  | 'CX1PG600001SEL1'(!)       = ''              | ''                 | 'CX1PG600001SEL1'          |'L0805'| 'NA'                           | 'IO'       | 'EMI FILTERCHIP BLM21PG600SN1D(60,3A)SELA'      | 'CHIP'         | ''          | ''   | '20230626'  
 'BLM18SN220TN1D/8000MA'        | 'SMLF'     | 'IND'    | 'CX220TN1001SEL1'(!)       = ''              | ''                 | 'CX220TN1001SEL1'          |'L0603'| 'BLM18SN220TN1D/8000MA'        | 'DISCRETE' | 'EMI FILTER BLM18SN(22,8000MA) SELASN'          | 'CHIP'         | ''          | ''   | '20230626'  
 'BLM18SN220TN1D/8000MA'        | 'SMLF'     | 'EMPTY'  | 'CX220TN1001SEL1'(!)       = ''              | ''                 | 'CX220TN1001SEL1'          |'L0603'| 'NA'                           | 'IO'       | 'EMI FILTER BLM18SN(22,8000MA) SELASN'          | 'CHIP'         | ''          | ''   | '20230626'  
 'HCB1608KF-221T25/2.5A'        | 'SMLF'     | 'IND'    | 'CX221T25000SEL1'(!)       = ''              | ''                 | 'CX221T25000SEL1'          |'L0603'| 'HCB1608KF-221T25/2.5A'        | 'DISCRETE' | 'EMI FILTER HCB1608KF-22(220,2.5A) SELASN'      | 'CHIP'         | ''          | ''   | '20230626'  
 'HCB1608KF-221T25/2.5A'        | 'SMLF'     | 'EMPTY'  | 'CX221T25000SEL1'(!)       = ''              | ''                 | 'CX221T25000SEL1'          |'L0603'| 'NA'                           | 'IO'       | 'EMI FILTER HCB1608KF-22(220,2.5A) SELASN'      | 'CHIP'         | ''          | ''   | '20230626'  
 'BLM15AG221SN1D/0.3A'          | 'SMLF'     | 'IND'    | 'CX5AG221104SEL1'(!)       = ''              | ''                 | 'CX5AG221104SEL1'          |'L0402'| 'BLM15AG221SN1D/0.3A'          | 'DISCRETE' | 'EMI FILTER BLM15AG221SN(220,0.3A) SELASN'      | 'CHIP'         | ''          | ''   | '20230626'  
 'BLM15AG221SN1D/0.3A'          | 'SMLF'     | 'EMPTY'  | 'CX5AG221104SEL1'(!)       = ''              | ''                 | 'CX5AG221104SEL1'          |'L0402'| 'NA'                           | 'IO'       | 'EMI FILTER BLM15AG221SN(220,0.3A) SELASN'      | 'CHIP'         | ''          | ''   | '20230626'  
 'BLM15PX600SN1D/2.5A'          | 'SMLF'     | 'IND'    | 'CX5PX600000SEL1'(!)       = ''              | ''                 | 'CX5PX600000SEL1'          |'L0402'| 'BLM15PX600SN1D/2.5A'          | 'DISCRETE' | 'EMI FILTER CHIP BLM15PX(60, 2.5A) SELASN'      | 'CHIP'         | ''          | ''   | '20230626'  
 'BLM15PX600SN1D/2.5A'          | 'SMLF'     | 'EMPTY'  | 'CX5PX600000SEL1'(!)       = ''              | ''                 | 'CX5PX600000SEL1'          |'L0402'| 'NA'                           | 'IO'       | 'EMI FILTER CHIP BLM15PX(60, 2.5A) SELASN'      | 'CHIP'         | ''          | ''   | '20230626'  
 'BLM18HE102SN1D/0.6A'          | 'SMLF'     | 'IND'    | 'CX8HE102000SEL1'(!)       = ''              | ''                 | 'CX8HE102000SEL1'          |'L0603'| 'BLM18HE102SN1D/0.6A'          | 'DISCRETE' | 'EMI FILTER BLM18HE102S(1000,0.6A) SELASN'      | 'CHIP'         | ''          | ''   | '20230626'  
 'BLM18HE102SN1D/0.6A'          | 'SMLF'     | 'EMPTY'  | 'CX8HE102000SEL1'(!)       = ''              | ''                 | 'CX8HE102000SEL1'          |'L0603'| 'NA'                           | 'IO'       | 'EMI FILTER BLM18HE102S(1000,0.6A) SELASN'      | 'CHIP'         | ''          | ''   | '20230626'  
 'BLM18SG221TN1D/2.5A'          | 'SMLF'     | 'IND'    | 'CX8SG221001SEL1'(!)       = ''              | ''                 | 'CX8SG221001SEL1'          |'L0603'| 'BLM18SG221TN1D/2.5A'          | 'DISCRETE' | 'EMI FILTER BLM18SG221TN1D(220,2.5A)SELA'       | 'CHIP'         | ''          | ''   | '20230626'  
 'BLM18SG221TN1D/2.5A'          | 'SMLF'     | 'EMPTY'  | 'CX8SG221001SEL1'(!)       = ''              | ''                 | 'CX8SG221001SEL1'          |'L0603'| 'NA'                           | 'IO'       | 'EMI FILTER BLM18SG221TN1D(220,2.5A)SELA'       | 'CHIP'         | ''          | ''   | '20230626'  
 'BLM18SG221TN1D/2.5A'          | 'SMLF'     | 'IND'    | 'CX8SG221001'(!)           = 'End of Design' | 'Comp-Approve'     | 'CX8SG221001'              |'L0603'| 'BLM18SG221TN1D/2.5A'          | 'DISCRETE' | 'EMI FILTER BLM18SG221TN1D(220.2.5A)'           | 'CHIP'         | ''          | ''   | '20230626'  
 'BLM18SG221TN1D/2.5A'          | 'SMLF'     | 'EMPTY'  | 'CX8SG221001'(!)           = 'End of Design' | 'Comp-Approve'     | 'CX8SG221001'              |'L0603'| 'NA'                           | 'IO'       | 'EMI FILTER BLM18SG221TN1D(220.2.5A)'           | 'CHIP'         | ''          | ''   | '20230626'  
 '100NH/80A'                    | 'SMLF'     | 'IND'    | 'CV+10^0EZ08'(!)           = ''              | ''                 | 'CV+10^0EZ08'              |'L_VLBU6565100T-R12L-1_6-5X6-5'| '100NH/80A'                    | 'DISCRETE' | 'IND SMD 100NH 15% 80A(PGL6312.101AHLT)'        | 'CHIP'         | ''          | ''   | '20230712'  
 '100NH/80A'                    | 'SMLF'     | 'EMPTY'  | 'CV+10^0EZ08'(!)           = ''              | ''                 | 'CV+10^0EZ08'              |'L_VLBU6565100T-R12L-1_6-5X6-5'| 'NA'                           | 'IO'       | 'IND SMD 100NH 15% 80A(PGL6312.101AHLT)'        | 'CHIP'         | ''          | ''   | '20230712'  
 '10UH/165MA'                   | 'SMLF'     | 'IND'    | 'CV01002MZ19'(!)           = ''              | ''                 | 'CV01002MZ19'              |'L1007'| '10UH/165MA'                   | 'DISCRETE' | 'IND SMD 10UH,+-20%,165MA,(LB2518T100M)'        | 'CHIP'         | ''          | ''   | '20230726'  
 '10UH/165MA'                   | 'SMLF'     | 'EMPTY'  | 'CV01002MZ19'(!)           = ''              | ''                 | 'CV01002MZ19'              |'L1007'| 'NA'                           | 'IO'       | 'IND SMD 10UH,+-20%,165MA,(LB2518T100M)'        | 'CHIP'         | ''          | ''   | '20230726'  
 '90NH/90A'                     | 'SMLF'     | 'IND'    | 'CVA90^0EZ02'(!)           = ''               | ''               | 'CVA90^0EZ02'              |'L_VLBU6565100T-R12L-1_6-5X6-5'| '90NH/90A'                     | 'DISCRETE' | 'IND SMD 90NH 15% 90A(PGL6312.900AHLT)'         | 'CHIP'         | ''          | ''   | '20230815'  
 '90NH/90A'                     | 'SMLF'     | 'EMPTY'  | 'CVA90^0EZ02'(!)           = ''               | ''               | 'CVA90^0EZ02'              |'L_VLBU6565100T-R12L-1_6-5X6-5'| 'NA'                           | 'IO'       | 'IND SMD 90NH 15% 90A(PGL6312.900AHLT)'         | 'CHIP'         | ''          | ''   | '20230815'  

END_PART

END.

